FILE_TYPE = MACRO_DRAWING;
SET COLOR_WIRE YELLOW;
SET COLOR_PROP ORANGE;
SET COLOR_DOT WHITE;
SET COLOR_ARC YELLOW;
SET COLOR_BODY GREEN;
SET COLOR_NOTE PURPLE;
SET PROP_DISPLAY VALUE;
SET PAGE_NUMBER P11;
FORCEADD GENOA_SP5..2
(-4550 3475);
FORCEPROP 1 LAST LOCATION U25
J 0
(-5195 6331);
DISPLAY 0.489362 (-5195 6331);
PAINT SKYBLUE (-5195 6331);
FORCEPROP 0 LAST $SEC 2
J 0
(-5175 6375);
DISPLAY 0.680851 (-5175 6375);
PAINT MONO (-5175 6375);
DISPLAY INVISIBLE (-5175 6375);
FORCEPROP 0 LAST CDS_SEC 2
J 0
(-5200 6300);
DISPLAY 1.021277 (-5200 6300);
DISPLAY INVISIBLE (-5200 6300);
FORCEPROP 0 LASTPIN (-5350 2875) $PN BC64
J 2
(-5360 2885);
DISPLAY 0.489362 (-5360 2885);
PAINT MONO (-5360 2885);
FORCEPROP 0 LASTPIN (-5350 2825) $PN BD63
J 2
(-5360 2835);
DISPLAY 0.489362 (-5360 2835);
PAINT MONO (-5360 2835);
FORCEPROP 0 LASTPIN (-5350 1725) $PN BF63
J 2
(-5360 1735);
DISPLAY 0.489362 (-5360 1735);
PAINT MONO (-5360 1735);
FORCEPROP 0 LASTPIN (-5350 1675) $PN BG64
J 2
(-5360 1685);
DISPLAY 0.489362 (-5360 1685);
PAINT MONO (-5360 1685);
FORCEPROP 0 LASTPIN (-5350 2025) $PN AT62
J 2
(-5360 2035);
DISPLAY 0.489362 (-5360 2035);
PAINT MONO (-5360 2035);
FORCEPROP 0 LASTPIN (-5350 1925) $PN AU62
J 2
(-5360 1935);
DISPLAY 0.489362 (-5360 1935);
PAINT MONO (-5360 1935);
FORCEPROP 0 LASTPIN (-5350 2725) $PN AV63
J 2
(-5360 2735);
DISPLAY 0.489362 (-5360 2735);
PAINT MONO (-5360 2735);
FORCEPROP 0 LASTPIN (-5350 2675) $PN AW62
J 2
(-5360 2685);
DISPLAY 0.489362 (-5360 2685);
PAINT MONO (-5360 2685);
FORCEPROP 0 LASTPIN (-5350 2575) $PN BN62
J 2
(-5360 2585);
DISPLAY 0.489362 (-5360 2585);
PAINT MONO (-5360 2585);
FORCEPROP 0 LASTPIN (-5350 1575) $PN AU64
J 2
(-5360 1585);
DISPLAY 0.489362 (-5360 1585);
PAINT MONO (-5360 1585);
FORCEPROP 0 LASTPIN (-5350 1525) $PN AV62
J 2
(-5360 1535);
DISPLAY 0.489362 (-5360 1535);
PAINT MONO (-5360 1535);
FORCEPROP 0 LASTPIN (-5350 1425) $PN BP62
J 2
(-5360 1435);
DISPLAY 0.489362 (-5360 1435);
PAINT MONO (-5360 1435);
FORCEPROP 0 LASTPIN (-5350 3725) $PN AW64
J 2
(-5360 3735);
DISPLAY 0.489362 (-5360 3735);
PAINT MONO (-5360 3735);
FORCEPROP 0 LASTPIN (-5350 3675) $PN AY63
J 2
(-5360 3685);
DISPLAY 0.489362 (-5360 3685);
PAINT MONO (-5360 3685);
FORCEPROP 0 LASTPIN (-5350 3625) $PN AY62
J 2
(-5360 3635);
DISPLAY 0.489362 (-5360 3635);
PAINT MONO (-5360 3635);
FORCEPROP 0 LASTPIN (-5350 3575) $PN BA62
J 2
(-5360 3585);
DISPLAY 0.489362 (-5360 3585);
PAINT MONO (-5360 3585);
FORCEPROP 0 LASTPIN (-5350 3525) $PN BA64
J 2
(-5360 3535);
DISPLAY 0.489362 (-5360 3535);
PAINT MONO (-5360 3535);
FORCEPROP 0 LASTPIN (-5350 3475) $PN BB63
J 2
(-5360 3485);
DISPLAY 0.489362 (-5360 3485);
PAINT MONO (-5360 3485);
FORCEPROP 0 LASTPIN (-5350 3425) $PN BB62
J 2
(-5360 3435);
DISPLAY 0.489362 (-5360 3435);
PAINT MONO (-5360 3435);
FORCEPROP 0 LASTPIN (-3750 2275) $PN AJ64
J 0
(-3740 2285);
DISPLAY 0.489362 (-3740 2285);
PAINT MONO (-3740 2285);
FORCEPROP 0 LASTPIN (-3750 2225) $PN AK62
J 0
(-3740 2235);
DISPLAY 0.489362 (-3740 2235);
PAINT MONO (-3740 2235);
FORCEPROP 0 LASTPIN (-3750 2175) $PN AK63
J 0
(-3740 2185);
DISPLAY 0.489362 (-3740 2185);
PAINT MONO (-3740 2185);
FORCEPROP 0 LASTPIN (-3750 2125) $PN AL62
J 0
(-3740 2135);
DISPLAY 0.489362 (-3740 2135);
PAINT MONO (-3740 2135);
FORCEPROP 0 LASTPIN (-3750 2075) $PN AN64
J 0
(-3740 2085);
DISPLAY 0.489362 (-3740 2085);
PAINT MONO (-3740 2085);
FORCEPROP 0 LASTPIN (-3750 2025) $PN AP62
J 0
(-3740 2035);
DISPLAY 0.489362 (-3740 2035);
PAINT MONO (-3740 2035);
FORCEPROP 0 LASTPIN (-3750 1975) $PN AP63
J 0
(-3740 1985);
DISPLAY 0.489362 (-3740 1985);
PAINT MONO (-3740 1985);
FORCEPROP 0 LASTPIN (-3750 1925) $PN AR62
J 0
(-3740 1935);
DISPLAY 0.489362 (-3740 1935);
PAINT MONO (-3740 1935);
FORCEPROP 0 LASTPIN (-3750 5875) $PN E64
J 0
(-3740 5885);
DISPLAY 0.489362 (-3740 5885);
PAINT MONO (-3740 5885);
FORCEPROP 0 LASTPIN (-3750 5825) $PN F62
J 0
(-3740 5835);
DISPLAY 0.489362 (-3740 5835);
PAINT MONO (-3740 5835);
FORCEPROP 0 LASTPIN (-3750 5775) $PN F63
J 0
(-3740 5785);
DISPLAY 0.489362 (-3740 5785);
PAINT MONO (-3740 5785);
FORCEPROP 0 LASTPIN (-3750 5725) $PN G62
J 0
(-3740 5735);
DISPLAY 0.489362 (-3740 5735);
PAINT MONO (-3740 5735);
FORCEPROP 0 LASTPIN (-3750 5675) $PN J64
J 0
(-3740 5685);
DISPLAY 0.489362 (-3740 5685);
PAINT MONO (-3740 5685);
FORCEPROP 0 LASTPIN (-3750 5625) $PN K62
J 0
(-3740 5635);
DISPLAY 0.489362 (-3740 5635);
PAINT MONO (-3740 5635);
FORCEPROP 0 LASTPIN (-3750 5575) $PN K63
J 0
(-3740 5585);
DISPLAY 0.489362 (-3740 5585);
PAINT MONO (-3740 5585);
FORCEPROP 0 LASTPIN (-3750 5525) $PN L62
J 0
(-3740 5535);
DISPLAY 0.489362 (-3740 5535);
PAINT MONO (-3740 5535);
FORCEPROP 0 LASTPIN (-3750 5425) $PN L64
J 0
(-3740 5435);
DISPLAY 0.489362 (-3740 5435);
PAINT MONO (-3740 5435);
FORCEPROP 0 LASTPIN (-3750 5375) $PN M62
J 0
(-3740 5385);
DISPLAY 0.489362 (-3740 5385);
PAINT MONO (-3740 5385);
FORCEPROP 0 LASTPIN (-3750 5325) $PN M63
J 0
(-3740 5335);
DISPLAY 0.489362 (-3740 5335);
PAINT MONO (-3740 5335);
FORCEPROP 0 LASTPIN (-3750 5275) $PN N62
J 0
(-3740 5285);
DISPLAY 0.489362 (-3740 5285);
PAINT MONO (-3740 5285);
FORCEPROP 0 LASTPIN (-3750 5225) $PN R64
J 0
(-3740 5235);
DISPLAY 0.489362 (-3740 5235);
PAINT MONO (-3740 5235);
FORCEPROP 0 LASTPIN (-3750 5175) $PN T62
J 0
(-3740 5185);
DISPLAY 0.489362 (-3740 5185);
PAINT MONO (-3740 5185);
FORCEPROP 0 LASTPIN (-3750 5125) $PN T63
J 0
(-3740 5135);
DISPLAY 0.489362 (-3740 5135);
PAINT MONO (-3740 5135);
FORCEPROP 0 LASTPIN (-3750 5075) $PN U62
J 0
(-3740 5085);
DISPLAY 0.489362 (-3740 5085);
PAINT MONO (-3740 5085);
FORCEPROP 0 LASTPIN (-3750 4975) $PN U64
J 0
(-3740 4985);
DISPLAY 0.489362 (-3740 4985);
PAINT MONO (-3740 4985);
FORCEPROP 0 LASTPIN (-3750 4925) $PN V62
J 0
(-3740 4935);
DISPLAY 0.489362 (-3740 4935);
PAINT MONO (-3740 4935);
FORCEPROP 0 LASTPIN (-3750 4875) $PN V63
J 0
(-3740 4885);
DISPLAY 0.489362 (-3740 4885);
PAINT MONO (-3740 4885);
FORCEPROP 0 LASTPIN (-3750 4825) $PN W62
J 0
(-3740 4835);
DISPLAY 0.489362 (-3740 4835);
PAINT MONO (-3740 4835);
FORCEPROP 0 LASTPIN (-3750 4775) $PN AA64
J 0
(-3740 4785);
DISPLAY 0.489362 (-3740 4785);
PAINT MONO (-3740 4785);
FORCEPROP 0 LASTPIN (-3750 4725) $PN AB62
J 0
(-3740 4735);
DISPLAY 0.489362 (-3740 4735);
PAINT MONO (-3740 4735);
FORCEPROP 0 LASTPIN (-3750 4675) $PN AB63
J 0
(-3740 4685);
DISPLAY 0.489362 (-3740 4685);
PAINT MONO (-3740 4685);
FORCEPROP 0 LASTPIN (-3750 4625) $PN AC62
J 0
(-3740 4635);
DISPLAY 0.489362 (-3740 4635);
PAINT MONO (-3740 4635);
FORCEPROP 0 LASTPIN (-3750 4525) $PN AC64
J 0
(-3740 4535);
DISPLAY 0.489362 (-3740 4535);
PAINT MONO (-3740 4535);
FORCEPROP 0 LASTPIN (-3750 4475) $PN AD62
J 0
(-3740 4485);
DISPLAY 0.489362 (-3740 4485);
PAINT MONO (-3740 4485);
FORCEPROP 0 LASTPIN (-3750 4425) $PN AD63
J 0
(-3740 4435);
DISPLAY 0.489362 (-3740 4435);
PAINT MONO (-3740 4435);
FORCEPROP 0 LASTPIN (-3750 4375) $PN AE62
J 0
(-3740 4385);
DISPLAY 0.489362 (-3740 4385);
PAINT MONO (-3740 4385);
FORCEPROP 0 LASTPIN (-3750 4325) $PN AG64
J 0
(-3740 4335);
DISPLAY 0.489362 (-3740 4335);
PAINT MONO (-3740 4335);
FORCEPROP 0 LASTPIN (-3750 4275) $PN AH62
J 0
(-3740 4285);
DISPLAY 0.489362 (-3740 4285);
PAINT MONO (-3740 4285);
FORCEPROP 0 LASTPIN (-3750 4225) $PN AH63
J 0
(-3740 4235);
DISPLAY 0.489362 (-3740 4235);
PAINT MONO (-3740 4235);
FORCEPROP 0 LASTPIN (-3750 4175) $PN AJ62
J 0
(-3740 4185);
DISPLAY 0.489362 (-3740 4185);
PAINT MONO (-3740 4185);
FORCEPROP 0 LASTPIN (-5350 5875) $PN G64
J 2
(-5360 5885);
DISPLAY 0.489362 (-5360 5885);
PAINT MONO (-5360 5885);
FORCEPROP 0 LASTPIN (-5350 5775) $PN N64
J 2
(-5360 5785);
DISPLAY 0.489362 (-5360 5785);
PAINT MONO (-5360 5785);
FORCEPROP 0 LASTPIN (-5350 5675) $PN W64
J 2
(-5360 5685);
DISPLAY 0.489362 (-5360 5685);
PAINT MONO (-5360 5685);
FORCEPROP 0 LASTPIN (-5350 5575) $PN AE64
J 2
(-5360 5585);
DISPLAY 0.489362 (-5360 5585);
PAINT MONO (-5360 5585);
FORCEPROP 0 LASTPIN (-5350 5475) $PN AL64
J 2
(-5360 5485);
DISPLAY 0.489362 (-5360 5485);
PAINT MONO (-5360 5485);
FORCEPROP 0 LASTPIN (-5350 5375) $PN J62
J 2
(-5360 5385);
DISPLAY 0.489362 (-5360 5385);
PAINT MONO (-5360 5385);
FORCEPROP 0 LASTPIN (-5350 5275) $PN R62
J 2
(-5360 5285);
DISPLAY 0.489362 (-5360 5285);
PAINT MONO (-5360 5285);
FORCEPROP 0 LASTPIN (-5350 5175) $PN AA62
J 2
(-5360 5185);
DISPLAY 0.489362 (-5360 5185);
PAINT MONO (-5360 5185);
FORCEPROP 0 LASTPIN (-5350 5075) $PN AG62
J 2
(-5360 5085);
DISPLAY 0.489362 (-5360 5085);
PAINT MONO (-5360 5085);
FORCEPROP 0 LASTPIN (-5350 4975) $PN AN62
J 2
(-5360 4985);
DISPLAY 0.489362 (-5360 4985);
PAINT MONO (-5360 4985);
FORCEPROP 0 LASTPIN (-5350 5825) $PN H63
J 2
(-5360 5835);
DISPLAY 0.489362 (-5360 5835);
PAINT MONO (-5360 5835);
FORCEPROP 0 LASTPIN (-5350 5725) $PN P63
J 2
(-5360 5735);
DISPLAY 0.489362 (-5360 5735);
PAINT MONO (-5360 5735);
FORCEPROP 0 LASTPIN (-5350 5625) $PN Y63
J 2
(-5360 5635);
DISPLAY 0.489362 (-5360 5635);
PAINT MONO (-5360 5635);
FORCEPROP 0 LASTPIN (-5350 5525) $PN AF63
J 2
(-5360 5535);
DISPLAY 0.489362 (-5360 5535);
PAINT MONO (-5360 5535);
FORCEPROP 0 LASTPIN (-5350 5425) $PN AM63
J 2
(-5360 5435);
DISPLAY 0.489362 (-5360 5435);
PAINT MONO (-5360 5435);
FORCEPROP 0 LASTPIN (-5350 5325) $PN H62
J 2
(-5360 5335);
DISPLAY 0.489362 (-5360 5335);
PAINT MONO (-5360 5335);
FORCEPROP 0 LASTPIN (-5350 5225) $PN P62
J 2
(-5360 5235);
DISPLAY 0.489362 (-5360 5235);
PAINT MONO (-5360 5235);
FORCEPROP 0 LASTPIN (-5350 5125) $PN Y62
J 2
(-5360 5135);
DISPLAY 0.489362 (-5360 5135);
PAINT MONO (-5360 5135);
FORCEPROP 0 LASTPIN (-5350 5025) $PN AF62
J 2
(-5360 5035);
DISPLAY 0.489362 (-5360 5035);
PAINT MONO (-5360 5035);
FORCEPROP 0 LASTPIN (-5350 4925) $PN AM62
J 2
(-5360 4935);
DISPLAY 0.489362 (-5360 4935);
PAINT MONO (-5360 4935);
FORCEPROP 0 LASTPIN (-5350 2475) $PN BC62
J 2
(-5360 2485);
DISPLAY 0.489362 (-5360 2485);
PAINT MONO (-5360 2485);
FORCEPROP 0 LASTPIN (-5350 2375) $PN BM62
J 2
(-5360 2385);
DISPLAY 0.489362 (-5360 2385);
PAINT MONO (-5360 2385);
FORCEPROP 0 LASTPIN (-5350 2325) $PN BN64
J 2
(-5360 2335);
DISPLAY 0.489362 (-5360 2335);
PAINT MONO (-5360 2335);
FORCEPROP 0 LASTPIN (-5350 2225) $PN BP63
J 2
(-5360 2235);
DISPLAY 0.489362 (-5360 2235);
PAINT MONO (-5360 2235);
FORCEPROP 0 LASTPIN (-5350 1325) $PN BL62
J 2
(-5360 1335);
DISPLAY 0.489362 (-5360 1335);
PAINT MONO (-5360 1335);
FORCEPROP 0 LASTPIN (-5350 1275) $PN BM63
J 2
(-5360 1285);
DISPLAY 0.489362 (-5360 1285);
PAINT MONO (-5360 1285);
FORCEPROP 0 LASTPIN (-5350 1175) $PN BR64
J 2
(-5360 1185);
DISPLAY 0.489362 (-5360 1185);
PAINT MONO (-5360 1185);
FORCEPROP 0 LASTPIN (-5350 3325) $PN BG62
J 2
(-5360 3335);
DISPLAY 0.489362 (-5360 3335);
PAINT MONO (-5360 3335);
FORCEPROP 0 LASTPIN (-5350 3275) $PN BH62
J 2
(-5360 3285);
DISPLAY 0.489362 (-5360 3285);
PAINT MONO (-5360 3285);
FORCEPROP 0 LASTPIN (-5350 3225) $PN BH63
J 2
(-5360 3235);
DISPLAY 0.489362 (-5360 3235);
PAINT MONO (-5360 3235);
FORCEPROP 0 LASTPIN (-5350 3175) $PN BJ64
J 2
(-5360 3185);
DISPLAY 0.489362 (-5360 3185);
PAINT MONO (-5360 3185);
FORCEPROP 0 LASTPIN (-5350 3125) $PN BJ62
J 2
(-5360 3135);
DISPLAY 0.489362 (-5360 3135);
PAINT MONO (-5360 3135);
FORCEPROP 0 LASTPIN (-5350 3075) $PN BK62
J 2
(-5360 3085);
DISPLAY 0.489362 (-5360 3085);
PAINT MONO (-5360 3085);
FORCEPROP 0 LASTPIN (-5350 3025) $PN BK63
J 2
(-5360 3035);
DISPLAY 0.489362 (-5360 3035);
PAINT MONO (-5360 3035);
FORCEPROP 0 LASTPIN (-3750 1825) $PN BY63
J 0
(-3740 1835);
DISPLAY 0.489362 (-3740 1835);
PAINT MONO (-3740 1835);
FORCEPROP 0 LASTPIN (-3750 1775) $PN CA62
J 0
(-3740 1785);
DISPLAY 0.489362 (-3740 1785);
PAINT MONO (-3740 1785);
FORCEPROP 0 LASTPIN (-3750 1725) $PN CA64
J 0
(-3740 1735);
DISPLAY 0.489362 (-3740 1735);
PAINT MONO (-3740 1735);
FORCEPROP 0 LASTPIN (-3750 1675) $PN CB62
J 0
(-3740 1685);
DISPLAY 0.489362 (-3740 1685);
PAINT MONO (-3740 1685);
FORCEPROP 0 LASTPIN (-3750 1625) $PN BT63
J 0
(-3740 1635);
DISPLAY 0.489362 (-3740 1635);
PAINT MONO (-3740 1635);
FORCEPROP 0 LASTPIN (-3750 1575) $PN BU62
J 0
(-3740 1585);
DISPLAY 0.489362 (-3740 1585);
PAINT MONO (-3740 1585);
FORCEPROP 0 LASTPIN (-3750 1525) $PN BU64
J 0
(-3740 1535);
DISPLAY 0.489362 (-3740 1535);
PAINT MONO (-3740 1535);
FORCEPROP 0 LASTPIN (-3750 1475) $PN BV62
J 0
(-3740 1485);
DISPLAY 0.489362 (-3740 1485);
PAINT MONO (-3740 1485);
FORCEPROP 0 LASTPIN (-3750 4075) $PN CB63
J 0
(-3740 4085);
DISPLAY 0.489362 (-3740 4085);
PAINT MONO (-3740 4085);
FORCEPROP 0 LASTPIN (-3750 4025) $PN CC62
J 0
(-3740 4035);
DISPLAY 0.489362 (-3740 4035);
PAINT MONO (-3740 4035);
FORCEPROP 0 LASTPIN (-3750 3975) $PN CC64
J 0
(-3740 3985);
DISPLAY 0.489362 (-3740 3985);
PAINT MONO (-3740 3985);
FORCEPROP 0 LASTPIN (-3750 3925) $PN CD62
J 0
(-3740 3935);
DISPLAY 0.489362 (-3740 3935);
PAINT MONO (-3740 3935);
FORCEPROP 0 LASTPIN (-3750 3875) $PN CF63
J 0
(-3740 3885);
DISPLAY 0.489362 (-3740 3885);
PAINT MONO (-3740 3885);
FORCEPROP 0 LASTPIN (-3750 3825) $PN CG62
J 0
(-3740 3835);
DISPLAY 0.489362 (-3740 3835);
PAINT MONO (-3740 3835);
FORCEPROP 0 LASTPIN (-3750 3775) $PN CG64
J 0
(-3740 3785);
DISPLAY 0.489362 (-3740 3785);
PAINT MONO (-3740 3785);
FORCEPROP 0 LASTPIN (-3750 3725) $PN CH62
J 0
(-3740 3735);
DISPLAY 0.489362 (-3740 3735);
PAINT MONO (-3740 3735);
FORCEPROP 0 LASTPIN (-3750 3625) $PN CH63
J 0
(-3740 3635);
DISPLAY 0.489362 (-3740 3635);
PAINT MONO (-3740 3635);
FORCEPROP 0 LASTPIN (-3750 3575) $PN CJ62
J 0
(-3740 3585);
DISPLAY 0.489362 (-3740 3585);
PAINT MONO (-3740 3585);
FORCEPROP 0 LASTPIN (-3750 3525) $PN CJ64
J 0
(-3740 3535);
DISPLAY 0.489362 (-3740 3535);
PAINT MONO (-3740 3535);
FORCEPROP 0 LASTPIN (-3750 3475) $PN CK62
J 0
(-3740 3485);
DISPLAY 0.489362 (-3740 3485);
PAINT MONO (-3740 3485);
FORCEPROP 0 LASTPIN (-3750 3425) $PN CM63
J 0
(-3740 3435);
DISPLAY 0.489362 (-3740 3435);
PAINT MONO (-3740 3435);
FORCEPROP 0 LASTPIN (-3750 3375) $PN CN62
J 0
(-3740 3385);
DISPLAY 0.489362 (-3740 3385);
PAINT MONO (-3740 3385);
FORCEPROP 0 LASTPIN (-3750 3325) $PN CN64
J 0
(-3740 3335);
DISPLAY 0.489362 (-3740 3335);
PAINT MONO (-3740 3335);
FORCEPROP 0 LASTPIN (-3750 3275) $PN CP62
J 0
(-3740 3285);
DISPLAY 0.489362 (-3740 3285);
PAINT MONO (-3740 3285);
FORCEPROP 0 LASTPIN (-3750 3175) $PN CP63
J 0
(-3740 3185);
DISPLAY 0.489362 (-3740 3185);
PAINT MONO (-3740 3185);
FORCEPROP 0 LASTPIN (-3750 3125) $PN CR62
J 0
(-3740 3135);
DISPLAY 0.489362 (-3740 3135);
PAINT MONO (-3740 3135);
FORCEPROP 0 LASTPIN (-3750 3075) $PN CR64
J 0
(-3740 3085);
DISPLAY 0.489362 (-3740 3085);
PAINT MONO (-3740 3085);
FORCEPROP 0 LASTPIN (-3750 3025) $PN CT62
J 0
(-3740 3035);
DISPLAY 0.489362 (-3740 3035);
PAINT MONO (-3740 3035);
FORCEPROP 0 LASTPIN (-3750 2975) $PN CV63
J 0
(-3740 2985);
DISPLAY 0.489362 (-3740 2985);
PAINT MONO (-3740 2985);
FORCEPROP 0 LASTPIN (-3750 2925) $PN CW62
J 0
(-3740 2935);
DISPLAY 0.489362 (-3740 2935);
PAINT MONO (-3740 2935);
FORCEPROP 0 LASTPIN (-3750 2875) $PN CW64
J 0
(-3740 2885);
DISPLAY 0.489362 (-3740 2885);
PAINT MONO (-3740 2885);
FORCEPROP 0 LASTPIN (-3750 2825) $PN CY62
J 0
(-3740 2835);
DISPLAY 0.489362 (-3740 2835);
PAINT MONO (-3740 2835);
FORCEPROP 0 LASTPIN (-3750 2725) $PN CY63
J 0
(-3740 2735);
DISPLAY 0.489362 (-3740 2735);
PAINT MONO (-3740 2735);
FORCEPROP 0 LASTPIN (-3750 2675) $PN DA62
J 0
(-3740 2685);
DISPLAY 0.489362 (-3740 2685);
PAINT MONO (-3740 2685);
FORCEPROP 0 LASTPIN (-3750 2625) $PN DA64
J 0
(-3740 2635);
DISPLAY 0.489362 (-3740 2635);
PAINT MONO (-3740 2635);
FORCEPROP 0 LASTPIN (-3750 2575) $PN DB62
J 0
(-3740 2585);
DISPLAY 0.489362 (-3740 2585);
PAINT MONO (-3740 2585);
FORCEPROP 0 LASTPIN (-3750 2525) $PN DD63
J 0
(-3740 2535);
DISPLAY 0.489362 (-3740 2535);
PAINT MONO (-3740 2535);
FORCEPROP 0 LASTPIN (-3750 2475) $PN DE62
J 0
(-3740 2485);
DISPLAY 0.489362 (-3740 2485);
PAINT MONO (-3740 2485);
FORCEPROP 0 LASTPIN (-3750 2425) $PN DE64
J 0
(-3740 2435);
DISPLAY 0.489362 (-3740 2435);
PAINT MONO (-3740 2435);
FORCEPROP 0 LASTPIN (-3750 2375) $PN DF62
J 0
(-3740 2385);
DISPLAY 0.489362 (-3740 2385);
PAINT MONO (-3740 2385);
FORCEPROP 0 LASTPIN (-5350 4825) $PN CD63
J 2
(-5360 4835);
DISPLAY 0.489362 (-5360 4835);
PAINT MONO (-5360 4835);
FORCEPROP 0 LASTPIN (-5350 4725) $PN CK63
J 2
(-5360 4735);
DISPLAY 0.489362 (-5360 4735);
PAINT MONO (-5360 4735);
FORCEPROP 0 LASTPIN (-5350 4625) $PN CT63
J 2
(-5360 4635);
DISPLAY 0.489362 (-5360 4635);
PAINT MONO (-5360 4635);
FORCEPROP 0 LASTPIN (-5350 4525) $PN DB63
J 2
(-5360 4535);
DISPLAY 0.489362 (-5360 4535);
PAINT MONO (-5360 4535);
FORCEPROP 0 LASTPIN (-5350 4425) $PN BY62
J 2
(-5360 4435);
DISPLAY 0.489362 (-5360 4435);
PAINT MONO (-5360 4435);
FORCEPROP 0 LASTPIN (-5350 4325) $PN CF62
J 2
(-5360 4335);
DISPLAY 0.489362 (-5360 4335);
PAINT MONO (-5360 4335);
FORCEPROP 0 LASTPIN (-5350 4225) $PN CM62
J 2
(-5360 4235);
DISPLAY 0.489362 (-5360 4235);
PAINT MONO (-5360 4235);
FORCEPROP 0 LASTPIN (-5350 4125) $PN CV62
J 2
(-5360 4135);
DISPLAY 0.489362 (-5360 4135);
PAINT MONO (-5360 4135);
FORCEPROP 0 LASTPIN (-5350 4025) $PN DD62
J 2
(-5360 4035);
DISPLAY 0.489362 (-5360 4035);
PAINT MONO (-5360 4035);
FORCEPROP 0 LASTPIN (-5350 3925) $PN BV63
J 2
(-5360 3935);
DISPLAY 0.489362 (-5360 3935);
PAINT MONO (-5360 3935);
FORCEPROP 0 LASTPIN (-5350 4775) $PN CE64
J 2
(-5360 4785);
DISPLAY 0.489362 (-5360 4785);
PAINT MONO (-5360 4785);
FORCEPROP 0 LASTPIN (-5350 4675) $PN CL64
J 2
(-5360 4685);
DISPLAY 0.489362 (-5360 4685);
PAINT MONO (-5360 4685);
FORCEPROP 0 LASTPIN (-5350 4575) $PN CU64
J 2
(-5360 4585);
DISPLAY 0.489362 (-5360 4585);
PAINT MONO (-5360 4585);
FORCEPROP 0 LASTPIN (-5350 4475) $PN DC64
J 2
(-5360 4485);
DISPLAY 0.489362 (-5360 4485);
PAINT MONO (-5360 4485);
FORCEPROP 0 LASTPIN (-5350 4375) $PN BW62
J 2
(-5360 4385);
DISPLAY 0.489362 (-5360 4385);
PAINT MONO (-5360 4385);
FORCEPROP 0 LASTPIN (-5350 4275) $PN CE62
J 2
(-5360 4285);
DISPLAY 0.489362 (-5360 4285);
PAINT MONO (-5360 4285);
FORCEPROP 0 LASTPIN (-5350 4175) $PN CL62
J 2
(-5360 4185);
DISPLAY 0.489362 (-5360 4185);
PAINT MONO (-5360 4185);
FORCEPROP 0 LASTPIN (-5350 4075) $PN CU62
J 2
(-5360 4085);
DISPLAY 0.489362 (-5360 4085);
PAINT MONO (-5360 4085);
FORCEPROP 0 LASTPIN (-5350 3975) $PN DC62
J 2
(-5360 3985);
DISPLAY 0.489362 (-5360 3985);
PAINT MONO (-5360 3985);
FORCEPROP 0 LASTPIN (-5350 3875) $PN BW64
J 2
(-5360 3885);
DISPLAY 0.489362 (-5360 3885);
PAINT MONO (-5360 3885);
FORCEPROP 0 LASTPIN (-5350 2125) $PN BL64
J 2
(-5360 2135);
DISPLAY 0.489362 (-5360 2135);
PAINT MONO (-5360 2135);
FORCEPROP 0 LASTPIN (-5350 1075) $PN BF62
J 2
(-5360 1085);
DISPLAY 0.489362 (-5360 1085);
PAINT MONO (-5360 1085);
FORCEPROP 2 LAST PART_TYPE SMLF
J 0
(-5200 6230);
DISPLAY 1.021277 (-5200 6230);
FORCEPROP 1 LAST MATERIAL IO
J 0
(-5195 6057);
DISPLAY 0.489362 (-5195 6057);
PAINT SKYBLUE (-5195 6057);
FORCEPROP 2 LAST VALUE SOCKET6096_13568-001
J 0
(-5200 6130);
DISPLAY 0.489362 (-5200 6130);
PAINT SKYBLUE (-5200 6130);
FORCEPROP 1 LAST PART_NUMBER DGA^6000030
J 0
(-5195 6184);
DISPLAY 0.489362 (-5195 6184);
PAINT SKYBLUE (-5195 6184);
FORCEPROP 1 LAST CDS_LMAN_SYM_OUTLINE -650,2550,650,-2550
J 0
(-4550 3475);
DISPLAY 0.468085 (-4550 3475);
PAINT GREEN (-4550 3475);
DISPLAY INVISIBLE (-4550 3475);
FORCEPROP 2 LAST CDS_LIB pure_quanta
J 0
(-4550 3475);
DISPLAY INVISIBLE (-4550 3475);
FORCEPROP 1 LAST NEEDS_NO_SIZE TRUE
J 0
(-4550 3475);
DISPLAY 0.723404 (-4550 3475);
PAINT GREEN (-4550 3475);
DISPLAY INVISIBLE (-4550 3475);
FORCEPROP 1 LAST PATH I171
J 0
(-4550 3475);
DISPLAY 0.723404 (-4550 3475);
PAINT GREEN (-4550 3475);
DISPLAY INVISIBLE (-4550 3475);
FORCEADD OFFPAGE..3
(-2550 5900);
FORCEPROP 2 LAST $XR0 86 
J 0
(-2336 5900);
DISPLAY 0.638298 (-2336 5900);
PAINT MONO (-2336 5900);
FORCEPROP 2 LAST PATH I172
J 0
(-2325 5950);
DISPLAY 1.021277 (-2325 5950);
DISPLAY INVISIBLE (-2325 5950);
FORCEPROP 1 LAST COMMENT_BODY TRUE
J 0
(-2600 5800);
DISPLAY 0.872340 (-2600 5800);
PAINT GREEN (-2600 5800);
DISPLAY INVISIBLE (-2600 5800);
FORCEPROP 1 LAST OFFPAGE TRUE
J 0
(-2225 5775);
DISPLAY 0.872340 (-2225 5775);
PAINT GREEN (-2225 5775);
DISPLAY INVISIBLE (-2225 5775);
FORCEPROP 2 LAST CDS_LIB mstr_standard
J 0
(-2550 5900);
DISPLAY 0.723404 (-2550 5900);
PAINT MONO (-2550 5900);
DISPLAY INVISIBLE (-2550 5900);
FORCEADD TAP..1
(-3275 5775);
FORCEPROP 3 LASTPIN (-3325 5775) SIG_NAME M_B_CPU0_SA_DQ<2>
J 0
(-3315 5785);
DISPLAY 0.659574 (-3315 5785);
PAINT MONO (-3315 5785);
DISPLAY INVISIBLE (-3315 5785);
FORCEPROP 1 LASTPIN (-3325 5775) BN 2
J 0
(-3337 5783);
DISPLAY 0.489362 (-3337 5783);
PAINT GREEN (-3337 5783);
FORCEPROP 2 LAST CDS_LIB mstr_standard
J 0
(-3275 5775);
DISPLAY 0.723404 (-3275 5775);
PAINT MONO (-3275 5775);
DISPLAY INVISIBLE (-3275 5775);
FORCEPROP 1 LAST BODY_TYPE PLUMBING
J 0
(-3275 5825);
DISPLAY 0.872340 (-3275 5825);
PAINT GREEN (-3275 5825);
DISPLAY INVISIBLE (-3275 5825);
FORCEPROP 1 LAST HDL_TAP TRUE
J 0
(-2950 5650);
DISPLAY 0.872340 (-2950 5650);
DISPLAY INVISIBLE (-2950 5650);
FORCEPROP 1 LAST PATH I173
J 0
(-3277 5775);
DISPLAY 0.872340 (-3277 5775);
PAINT GREEN (-3277 5775);
DISPLAY INVISIBLE (-3277 5775);
FORCEADD TAP..1
(-3275 5825);
FORCEPROP 3 LASTPIN (-3325 5825) SIG_NAME M_B_CPU0_SA_DQ<1>
J 0
(-3315 5835);
DISPLAY 0.659574 (-3315 5835);
PAINT MONO (-3315 5835);
DISPLAY INVISIBLE (-3315 5835);
FORCEPROP 1 LASTPIN (-3325 5825) BN 1
J 0
(-3337 5833);
DISPLAY 0.489362 (-3337 5833);
PAINT GREEN (-3337 5833);
FORCEPROP 2 LAST CDS_LIB mstr_standard
J 0
(-3275 5825);
DISPLAY 0.723404 (-3275 5825);
PAINT MONO (-3275 5825);
DISPLAY INVISIBLE (-3275 5825);
FORCEPROP 1 LAST BODY_TYPE PLUMBING
J 0
(-3275 5875);
DISPLAY 0.872340 (-3275 5875);
PAINT GREEN (-3275 5875);
DISPLAY INVISIBLE (-3275 5875);
FORCEPROP 1 LAST HDL_TAP TRUE
J 0
(-2950 5700);
DISPLAY 0.872340 (-2950 5700);
DISPLAY INVISIBLE (-2950 5700);
FORCEPROP 1 LAST PATH I174
J 0
(-3277 5825);
DISPLAY 0.872340 (-3277 5825);
PAINT GREEN (-3277 5825);
DISPLAY INVISIBLE (-3277 5825);
FORCEADD TAP..1
(-3275 5875);
FORCEPROP 3 LASTPIN (-3325 5875) SIG_NAME M_B_CPU0_SA_DQ<0>
J 0
(-3315 5885);
DISPLAY 0.659574 (-3315 5885);
PAINT MONO (-3315 5885);
DISPLAY INVISIBLE (-3315 5885);
FORCEPROP 1 LASTPIN (-3325 5875) BN 0
J 0
(-3337 5883);
DISPLAY 0.489362 (-3337 5883);
PAINT GREEN (-3337 5883);
FORCEPROP 2 LAST CDS_LIB mstr_standard
J 0
(-3275 5875);
DISPLAY 0.723404 (-3275 5875);
PAINT MONO (-3275 5875);
DISPLAY INVISIBLE (-3275 5875);
FORCEPROP 1 LAST BODY_TYPE PLUMBING
J 0
(-3275 5925);
DISPLAY 0.872340 (-3275 5925);
PAINT GREEN (-3275 5925);
DISPLAY INVISIBLE (-3275 5925);
FORCEPROP 1 LAST HDL_TAP TRUE
J 0
(-2950 5750);
DISPLAY 0.872340 (-2950 5750);
DISPLAY INVISIBLE (-2950 5750);
FORCEPROP 1 LAST PATH I175
J 0
(-3277 5875);
DISPLAY 0.872340 (-3277 5875);
PAINT GREEN (-3277 5875);
DISPLAY INVISIBLE (-3277 5875);
FORCEADD TAP..1
(-3275 5675);
FORCEPROP 3 LASTPIN (-3325 5675) SIG_NAME M_B_CPU0_SA_DQ<4>
J 0
(-3315 5685);
DISPLAY 0.659574 (-3315 5685);
PAINT MONO (-3315 5685);
DISPLAY INVISIBLE (-3315 5685);
FORCEPROP 1 LASTPIN (-3325 5675) BN 4
J 0
(-3337 5683);
DISPLAY 0.489362 (-3337 5683);
PAINT GREEN (-3337 5683);
FORCEPROP 2 LAST CDS_LIB mstr_standard
J 0
(-3275 5675);
DISPLAY 0.723404 (-3275 5675);
PAINT MONO (-3275 5675);
DISPLAY INVISIBLE (-3275 5675);
FORCEPROP 1 LAST BODY_TYPE PLUMBING
J 0
(-3275 5725);
DISPLAY 0.872340 (-3275 5725);
PAINT GREEN (-3275 5725);
DISPLAY INVISIBLE (-3275 5725);
FORCEPROP 1 LAST HDL_TAP TRUE
J 0
(-2950 5550);
DISPLAY 0.872340 (-2950 5550);
DISPLAY INVISIBLE (-2950 5550);
FORCEPROP 1 LAST PATH I176
J 0
(-3277 5675);
DISPLAY 0.872340 (-3277 5675);
PAINT GREEN (-3277 5675);
DISPLAY INVISIBLE (-3277 5675);
FORCEADD TAP..1
(-3275 5725);
FORCEPROP 3 LASTPIN (-3325 5725) SIG_NAME M_B_CPU0_SA_DQ<3>
J 0
(-3315 5735);
DISPLAY 0.659574 (-3315 5735);
PAINT MONO (-3315 5735);
DISPLAY INVISIBLE (-3315 5735);
FORCEPROP 1 LASTPIN (-3325 5725) BN 3
J 0
(-3337 5733);
DISPLAY 0.489362 (-3337 5733);
PAINT GREEN (-3337 5733);
FORCEPROP 2 LAST CDS_LIB mstr_standard
J 0
(-3275 5725);
DISPLAY 0.723404 (-3275 5725);
PAINT MONO (-3275 5725);
DISPLAY INVISIBLE (-3275 5725);
FORCEPROP 1 LAST BODY_TYPE PLUMBING
J 0
(-3275 5775);
DISPLAY 0.872340 (-3275 5775);
PAINT GREEN (-3275 5775);
DISPLAY INVISIBLE (-3275 5775);
FORCEPROP 1 LAST HDL_TAP TRUE
J 0
(-2950 5600);
DISPLAY 0.872340 (-2950 5600);
DISPLAY INVISIBLE (-2950 5600);
FORCEPROP 1 LAST PATH I177
J 0
(-3277 5725);
DISPLAY 0.872340 (-3277 5725);
PAINT GREEN (-3277 5725);
DISPLAY INVISIBLE (-3277 5725);
FORCEADD TAP..1
(-3275 5625);
FORCEPROP 3 LASTPIN (-3325 5625) SIG_NAME M_B_CPU0_SA_DQ<5>
J 0
(-3315 5635);
DISPLAY 0.659574 (-3315 5635);
PAINT MONO (-3315 5635);
DISPLAY INVISIBLE (-3315 5635);
FORCEPROP 1 LASTPIN (-3325 5625) BN 5
J 0
(-3337 5633);
DISPLAY 0.489362 (-3337 5633);
PAINT GREEN (-3337 5633);
FORCEPROP 2 LAST CDS_LIB mstr_standard
J 0
(-3275 5625);
DISPLAY 0.723404 (-3275 5625);
PAINT MONO (-3275 5625);
DISPLAY INVISIBLE (-3275 5625);
FORCEPROP 1 LAST BODY_TYPE PLUMBING
J 0
(-3275 5675);
DISPLAY 0.872340 (-3275 5675);
PAINT GREEN (-3275 5675);
DISPLAY INVISIBLE (-3275 5675);
FORCEPROP 1 LAST HDL_TAP TRUE
J 0
(-2950 5500);
DISPLAY 0.872340 (-2950 5500);
DISPLAY INVISIBLE (-2950 5500);
FORCEPROP 1 LAST PATH I178
J 0
(-3277 5625);
DISPLAY 0.872340 (-3277 5625);
PAINT GREEN (-3277 5625);
DISPLAY INVISIBLE (-3277 5625);
FORCEADD TAP..1
(-3275 5575);
FORCEPROP 3 LASTPIN (-3325 5575) SIG_NAME M_B_CPU0_SA_DQ<6>
J 0
(-3315 5585);
DISPLAY 0.659574 (-3315 5585);
PAINT MONO (-3315 5585);
DISPLAY INVISIBLE (-3315 5585);
FORCEPROP 1 LASTPIN (-3325 5575) BN 6
J 0
(-3337 5583);
DISPLAY 0.489362 (-3337 5583);
PAINT GREEN (-3337 5583);
FORCEPROP 2 LAST CDS_LIB mstr_standard
J 0
(-3275 5575);
DISPLAY 0.723404 (-3275 5575);
PAINT MONO (-3275 5575);
DISPLAY INVISIBLE (-3275 5575);
FORCEPROP 1 LAST BODY_TYPE PLUMBING
J 0
(-3275 5625);
DISPLAY 0.872340 (-3275 5625);
PAINT GREEN (-3275 5625);
DISPLAY INVISIBLE (-3275 5625);
FORCEPROP 1 LAST HDL_TAP TRUE
J 0
(-2950 5450);
DISPLAY 0.872340 (-2950 5450);
DISPLAY INVISIBLE (-2950 5450);
FORCEPROP 1 LAST PATH I179
J 0
(-3277 5575);
DISPLAY 0.872340 (-3277 5575);
PAINT GREEN (-3277 5575);
DISPLAY INVISIBLE (-3277 5575);
FORCEADD TAP..1
(-3275 5525);
FORCEPROP 3 LASTPIN (-3325 5525) SIG_NAME M_B_CPU0_SA_DQ<7>
J 0
(-3315 5535);
DISPLAY 0.659574 (-3315 5535);
PAINT MONO (-3315 5535);
DISPLAY INVISIBLE (-3315 5535);
FORCEPROP 1 LASTPIN (-3325 5525) BN 7
J 0
(-3337 5533);
DISPLAY 0.489362 (-3337 5533);
PAINT GREEN (-3337 5533);
FORCEPROP 2 LAST CDS_LIB mstr_standard
J 0
(-3275 5525);
DISPLAY 0.723404 (-3275 5525);
PAINT MONO (-3275 5525);
DISPLAY INVISIBLE (-3275 5525);
FORCEPROP 1 LAST BODY_TYPE PLUMBING
J 0
(-3275 5575);
DISPLAY 0.872340 (-3275 5575);
PAINT GREEN (-3275 5575);
DISPLAY INVISIBLE (-3275 5575);
FORCEPROP 1 LAST HDL_TAP TRUE
J 0
(-2950 5400);
DISPLAY 0.872340 (-2950 5400);
DISPLAY INVISIBLE (-2950 5400);
FORCEPROP 1 LAST PATH I180
J 0
(-3277 5525);
DISPLAY 0.872340 (-3277 5525);
PAINT GREEN (-3277 5525);
DISPLAY INVISIBLE (-3277 5525);
FORCEADD TAP..1
(-3275 5425);
FORCEPROP 3 LASTPIN (-3325 5425) SIG_NAME M_B_CPU0_SA_DQ<8>
J 0
(-3315 5435);
DISPLAY 0.659574 (-3315 5435);
PAINT MONO (-3315 5435);
DISPLAY INVISIBLE (-3315 5435);
FORCEPROP 1 LASTPIN (-3325 5425) BN 8
J 0
(-3337 5433);
DISPLAY 0.489362 (-3337 5433);
PAINT GREEN (-3337 5433);
FORCEPROP 2 LAST CDS_LIB mstr_standard
J 0
(-3275 5425);
DISPLAY 0.723404 (-3275 5425);
PAINT MONO (-3275 5425);
DISPLAY INVISIBLE (-3275 5425);
FORCEPROP 1 LAST BODY_TYPE PLUMBING
J 0
(-3275 5475);
DISPLAY 0.872340 (-3275 5475);
PAINT GREEN (-3275 5475);
DISPLAY INVISIBLE (-3275 5475);
FORCEPROP 1 LAST HDL_TAP TRUE
J 0
(-2950 5300);
DISPLAY 0.872340 (-2950 5300);
DISPLAY INVISIBLE (-2950 5300);
FORCEPROP 1 LAST PATH I181
J 0
(-3277 5425);
DISPLAY 0.872340 (-3277 5425);
PAINT GREEN (-3277 5425);
DISPLAY INVISIBLE (-3277 5425);
FORCEADD TAP..1
(-3275 5275);
FORCEPROP 3 LASTPIN (-3325 5275) SIG_NAME M_B_CPU0_SA_DQ<11>
J 0
(-3315 5285);
DISPLAY 0.659574 (-3315 5285);
PAINT MONO (-3315 5285);
DISPLAY INVISIBLE (-3315 5285);
FORCEPROP 1 LASTPIN (-3325 5275) BN 11
J 0
(-3337 5283);
DISPLAY 0.489362 (-3337 5283);
PAINT GREEN (-3337 5283);
FORCEPROP 2 LAST CDS_LIB mstr_standard
J 0
(-3275 5275);
DISPLAY 0.723404 (-3275 5275);
PAINT MONO (-3275 5275);
DISPLAY INVISIBLE (-3275 5275);
FORCEPROP 1 LAST BODY_TYPE PLUMBING
J 0
(-3275 5325);
DISPLAY 0.872340 (-3275 5325);
PAINT GREEN (-3275 5325);
DISPLAY INVISIBLE (-3275 5325);
FORCEPROP 1 LAST HDL_TAP TRUE
J 0
(-2950 5150);
DISPLAY 0.872340 (-2950 5150);
DISPLAY INVISIBLE (-2950 5150);
FORCEPROP 1 LAST PATH I182
J 0
(-3277 5275);
DISPLAY 0.872340 (-3277 5275);
PAINT GREEN (-3277 5275);
DISPLAY INVISIBLE (-3277 5275);
FORCEADD TAP..1
(-3275 5325);
FORCEPROP 3 LASTPIN (-3325 5325) SIG_NAME M_B_CPU0_SA_DQ<10>
J 0
(-3315 5335);
DISPLAY 0.659574 (-3315 5335);
PAINT MONO (-3315 5335);
DISPLAY INVISIBLE (-3315 5335);
FORCEPROP 1 LASTPIN (-3325 5325) BN 10
J 0
(-3337 5333);
DISPLAY 0.489362 (-3337 5333);
PAINT GREEN (-3337 5333);
FORCEPROP 2 LAST CDS_LIB mstr_standard
J 0
(-3275 5325);
DISPLAY 0.723404 (-3275 5325);
PAINT MONO (-3275 5325);
DISPLAY INVISIBLE (-3275 5325);
FORCEPROP 1 LAST BODY_TYPE PLUMBING
J 0
(-3275 5375);
DISPLAY 0.872340 (-3275 5375);
PAINT GREEN (-3275 5375);
DISPLAY INVISIBLE (-3275 5375);
FORCEPROP 1 LAST HDL_TAP TRUE
J 0
(-2950 5200);
DISPLAY 0.872340 (-2950 5200);
DISPLAY INVISIBLE (-2950 5200);
FORCEPROP 1 LAST PATH I183
J 0
(-3277 5325);
DISPLAY 0.872340 (-3277 5325);
PAINT GREEN (-3277 5325);
DISPLAY INVISIBLE (-3277 5325);
FORCEADD TAP..1
(-3275 5375);
FORCEPROP 3 LASTPIN (-3325 5375) SIG_NAME M_B_CPU0_SA_DQ<9>
J 0
(-3315 5385);
DISPLAY 0.659574 (-3315 5385);
PAINT MONO (-3315 5385);
DISPLAY INVISIBLE (-3315 5385);
FORCEPROP 1 LASTPIN (-3325 5375) BN 9
J 0
(-3337 5383);
DISPLAY 0.489362 (-3337 5383);
PAINT GREEN (-3337 5383);
FORCEPROP 2 LAST CDS_LIB mstr_standard
J 0
(-3275 5375);
DISPLAY 0.723404 (-3275 5375);
PAINT MONO (-3275 5375);
DISPLAY INVISIBLE (-3275 5375);
FORCEPROP 1 LAST BODY_TYPE PLUMBING
J 0
(-3275 5425);
DISPLAY 0.872340 (-3275 5425);
PAINT GREEN (-3275 5425);
DISPLAY INVISIBLE (-3275 5425);
FORCEPROP 1 LAST HDL_TAP TRUE
J 0
(-2950 5250);
DISPLAY 0.872340 (-2950 5250);
DISPLAY INVISIBLE (-2950 5250);
FORCEPROP 1 LAST PATH I184
J 0
(-3277 5375);
DISPLAY 0.872340 (-3277 5375);
PAINT GREEN (-3277 5375);
DISPLAY INVISIBLE (-3277 5375);
FORCEADD TAP..1
(-3275 5225);
FORCEPROP 3 LASTPIN (-3325 5225) SIG_NAME M_B_CPU0_SA_DQ<12>
J 0
(-3315 5235);
DISPLAY 0.659574 (-3315 5235);
PAINT MONO (-3315 5235);
DISPLAY INVISIBLE (-3315 5235);
FORCEPROP 1 LASTPIN (-3325 5225) BN 12
J 0
(-3337 5233);
DISPLAY 0.489362 (-3337 5233);
PAINT GREEN (-3337 5233);
FORCEPROP 2 LAST CDS_LIB mstr_standard
J 0
(-3275 5225);
DISPLAY 0.723404 (-3275 5225);
PAINT MONO (-3275 5225);
DISPLAY INVISIBLE (-3275 5225);
FORCEPROP 1 LAST BODY_TYPE PLUMBING
J 0
(-3275 5275);
DISPLAY 0.872340 (-3275 5275);
PAINT GREEN (-3275 5275);
DISPLAY INVISIBLE (-3275 5275);
FORCEPROP 1 LAST HDL_TAP TRUE
J 0
(-2950 5100);
DISPLAY 0.872340 (-2950 5100);
DISPLAY INVISIBLE (-2950 5100);
FORCEPROP 1 LAST PATH I185
J 0
(-3277 5225);
DISPLAY 0.872340 (-3277 5225);
PAINT GREEN (-3277 5225);
DISPLAY INVISIBLE (-3277 5225);
FORCEADD TAP..1
(-3275 5175);
FORCEPROP 3 LASTPIN (-3325 5175) SIG_NAME M_B_CPU0_SA_DQ<13>
J 0
(-3315 5185);
DISPLAY 0.659574 (-3315 5185);
PAINT MONO (-3315 5185);
DISPLAY INVISIBLE (-3315 5185);
FORCEPROP 1 LASTPIN (-3325 5175) BN 13
J 0
(-3337 5183);
DISPLAY 0.489362 (-3337 5183);
PAINT GREEN (-3337 5183);
FORCEPROP 2 LAST CDS_LIB mstr_standard
J 0
(-3275 5175);
DISPLAY 0.723404 (-3275 5175);
PAINT MONO (-3275 5175);
DISPLAY INVISIBLE (-3275 5175);
FORCEPROP 1 LAST BODY_TYPE PLUMBING
J 0
(-3275 5225);
DISPLAY 0.872340 (-3275 5225);
PAINT GREEN (-3275 5225);
DISPLAY INVISIBLE (-3275 5225);
FORCEPROP 1 LAST HDL_TAP TRUE
J 0
(-2950 5050);
DISPLAY 0.872340 (-2950 5050);
DISPLAY INVISIBLE (-2950 5050);
FORCEPROP 1 LAST PATH I186
J 0
(-3277 5175);
DISPLAY 0.872340 (-3277 5175);
PAINT GREEN (-3277 5175);
DISPLAY INVISIBLE (-3277 5175);
FORCEADD TAP..1
(-3275 5125);
FORCEPROP 3 LASTPIN (-3325 5125) SIG_NAME M_B_CPU0_SA_DQ<14>
J 0
(-3315 5135);
DISPLAY 0.659574 (-3315 5135);
PAINT MONO (-3315 5135);
DISPLAY INVISIBLE (-3315 5135);
FORCEPROP 1 LASTPIN (-3325 5125) BN 14
J 0
(-3337 5133);
DISPLAY 0.489362 (-3337 5133);
PAINT GREEN (-3337 5133);
FORCEPROP 2 LAST CDS_LIB mstr_standard
J 0
(-3275 5125);
DISPLAY 0.723404 (-3275 5125);
PAINT MONO (-3275 5125);
DISPLAY INVISIBLE (-3275 5125);
FORCEPROP 1 LAST BODY_TYPE PLUMBING
J 0
(-3275 5175);
DISPLAY 0.872340 (-3275 5175);
PAINT GREEN (-3275 5175);
DISPLAY INVISIBLE (-3275 5175);
FORCEPROP 1 LAST HDL_TAP TRUE
J 0
(-2950 5000);
DISPLAY 0.872340 (-2950 5000);
DISPLAY INVISIBLE (-2950 5000);
FORCEPROP 1 LAST PATH I187
J 0
(-3277 5125);
DISPLAY 0.872340 (-3277 5125);
PAINT GREEN (-3277 5125);
DISPLAY INVISIBLE (-3277 5125);
FORCEADD TAP..1
(-3275 5075);
FORCEPROP 3 LASTPIN (-3325 5075) SIG_NAME M_B_CPU0_SA_DQ<15>
J 0
(-3315 5085);
DISPLAY 0.659574 (-3315 5085);
PAINT MONO (-3315 5085);
DISPLAY INVISIBLE (-3315 5085);
FORCEPROP 1 LASTPIN (-3325 5075) BN 15
J 0
(-3337 5083);
DISPLAY 0.489362 (-3337 5083);
PAINT GREEN (-3337 5083);
FORCEPROP 2 LAST CDS_LIB mstr_standard
J 0
(-3275 5075);
DISPLAY 0.723404 (-3275 5075);
PAINT MONO (-3275 5075);
DISPLAY INVISIBLE (-3275 5075);
FORCEPROP 1 LAST BODY_TYPE PLUMBING
J 0
(-3275 5125);
DISPLAY 0.872340 (-3275 5125);
PAINT GREEN (-3275 5125);
DISPLAY INVISIBLE (-3275 5125);
FORCEPROP 1 LAST HDL_TAP TRUE
J 0
(-2950 4950);
DISPLAY 0.872340 (-2950 4950);
DISPLAY INVISIBLE (-2950 4950);
FORCEPROP 1 LAST PATH I188
J 0
(-3277 5075);
DISPLAY 0.872340 (-3277 5075);
PAINT GREEN (-3277 5075);
DISPLAY INVISIBLE (-3277 5075);
FORCEADD TAP..1
(-3275 4975);
FORCEPROP 3 LASTPIN (-3325 4975) SIG_NAME M_B_CPU0_SA_DQ<16>
J 0
(-3315 4985);
DISPLAY 0.659574 (-3315 4985);
PAINT MONO (-3315 4985);
DISPLAY INVISIBLE (-3315 4985);
FORCEPROP 1 LASTPIN (-3325 4975) BN 16
J 0
(-3337 4983);
DISPLAY 0.489362 (-3337 4983);
PAINT GREEN (-3337 4983);
FORCEPROP 2 LAST CDS_LIB mstr_standard
J 0
(-3275 4975);
DISPLAY 0.723404 (-3275 4975);
PAINT MONO (-3275 4975);
DISPLAY INVISIBLE (-3275 4975);
FORCEPROP 1 LAST BODY_TYPE PLUMBING
J 0
(-3275 5025);
DISPLAY 0.872340 (-3275 5025);
PAINT GREEN (-3275 5025);
DISPLAY INVISIBLE (-3275 5025);
FORCEPROP 1 LAST HDL_TAP TRUE
J 0
(-2950 4850);
DISPLAY 0.872340 (-2950 4850);
DISPLAY INVISIBLE (-2950 4850);
FORCEPROP 1 LAST PATH I189
J 0
(-3277 4975);
DISPLAY 0.872340 (-3277 4975);
PAINT GREEN (-3277 4975);
DISPLAY INVISIBLE (-3277 4975);
FORCEADD TAP..1
(-3275 4925);
FORCEPROP 3 LASTPIN (-3325 4925) SIG_NAME M_B_CPU0_SA_DQ<17>
J 0
(-3315 4935);
DISPLAY 0.659574 (-3315 4935);
PAINT MONO (-3315 4935);
DISPLAY INVISIBLE (-3315 4935);
FORCEPROP 1 LASTPIN (-3325 4925) BN 17
J 0
(-3337 4933);
DISPLAY 0.489362 (-3337 4933);
PAINT GREEN (-3337 4933);
FORCEPROP 2 LAST CDS_LIB mstr_standard
J 0
(-3275 4925);
DISPLAY 0.723404 (-3275 4925);
PAINT MONO (-3275 4925);
DISPLAY INVISIBLE (-3275 4925);
FORCEPROP 1 LAST BODY_TYPE PLUMBING
J 0
(-3275 4975);
DISPLAY 0.872340 (-3275 4975);
PAINT GREEN (-3275 4975);
DISPLAY INVISIBLE (-3275 4975);
FORCEPROP 1 LAST HDL_TAP TRUE
J 0
(-2950 4800);
DISPLAY 0.872340 (-2950 4800);
DISPLAY INVISIBLE (-2950 4800);
FORCEPROP 1 LAST PATH I190
J 0
(-3277 4925);
DISPLAY 0.872340 (-3277 4925);
PAINT GREEN (-3277 4925);
DISPLAY INVISIBLE (-3277 4925);
FORCEADD TAP..1
(-3275 4875);
FORCEPROP 3 LASTPIN (-3325 4875) SIG_NAME M_B_CPU0_SA_DQ<18>
J 0
(-3315 4885);
DISPLAY 0.659574 (-3315 4885);
PAINT MONO (-3315 4885);
DISPLAY INVISIBLE (-3315 4885);
FORCEPROP 1 LASTPIN (-3325 4875) BN 18
J 0
(-3337 4883);
DISPLAY 0.489362 (-3337 4883);
PAINT GREEN (-3337 4883);
FORCEPROP 2 LAST CDS_LIB mstr_standard
J 0
(-3275 4875);
DISPLAY 0.723404 (-3275 4875);
PAINT MONO (-3275 4875);
DISPLAY INVISIBLE (-3275 4875);
FORCEPROP 1 LAST BODY_TYPE PLUMBING
J 0
(-3275 4925);
DISPLAY 0.872340 (-3275 4925);
PAINT GREEN (-3275 4925);
DISPLAY INVISIBLE (-3275 4925);
FORCEPROP 1 LAST HDL_TAP TRUE
J 0
(-2950 4750);
DISPLAY 0.872340 (-2950 4750);
DISPLAY INVISIBLE (-2950 4750);
FORCEPROP 1 LAST PATH I191
J 0
(-3277 4875);
DISPLAY 0.872340 (-3277 4875);
PAINT GREEN (-3277 4875);
DISPLAY INVISIBLE (-3277 4875);
FORCEADD TAP..1
(-3275 4775);
FORCEPROP 3 LASTPIN (-3325 4775) SIG_NAME M_B_CPU0_SA_DQ<20>
J 0
(-3315 4785);
DISPLAY 0.659574 (-3315 4785);
PAINT MONO (-3315 4785);
DISPLAY INVISIBLE (-3315 4785);
FORCEPROP 1 LASTPIN (-3325 4775) BN 20
J 0
(-3337 4783);
DISPLAY 0.489362 (-3337 4783);
PAINT GREEN (-3337 4783);
FORCEPROP 2 LAST CDS_LIB mstr_standard
J 0
(-3275 4775);
DISPLAY 0.723404 (-3275 4775);
PAINT MONO (-3275 4775);
DISPLAY INVISIBLE (-3275 4775);
FORCEPROP 1 LAST BODY_TYPE PLUMBING
J 0
(-3275 4825);
DISPLAY 0.872340 (-3275 4825);
PAINT GREEN (-3275 4825);
DISPLAY INVISIBLE (-3275 4825);
FORCEPROP 1 LAST HDL_TAP TRUE
J 0
(-2950 4650);
DISPLAY 0.872340 (-2950 4650);
DISPLAY INVISIBLE (-2950 4650);
FORCEPROP 1 LAST PATH I192
J 0
(-3277 4775);
DISPLAY 0.872340 (-3277 4775);
PAINT GREEN (-3277 4775);
DISPLAY INVISIBLE (-3277 4775);
FORCEADD TAP..1
(-3275 4825);
FORCEPROP 3 LASTPIN (-3325 4825) SIG_NAME M_B_CPU0_SA_DQ<19>
J 0
(-3315 4835);
DISPLAY 0.659574 (-3315 4835);
PAINT MONO (-3315 4835);
DISPLAY INVISIBLE (-3315 4835);
FORCEPROP 1 LASTPIN (-3325 4825) BN 19
J 0
(-3337 4833);
DISPLAY 0.489362 (-3337 4833);
PAINT GREEN (-3337 4833);
FORCEPROP 2 LAST CDS_LIB mstr_standard
J 0
(-3275 4825);
DISPLAY 0.723404 (-3275 4825);
PAINT MONO (-3275 4825);
DISPLAY INVISIBLE (-3275 4825);
FORCEPROP 1 LAST BODY_TYPE PLUMBING
J 0
(-3275 4875);
DISPLAY 0.872340 (-3275 4875);
PAINT GREEN (-3275 4875);
DISPLAY INVISIBLE (-3275 4875);
FORCEPROP 1 LAST HDL_TAP TRUE
J 0
(-2950 4700);
DISPLAY 0.872340 (-2950 4700);
DISPLAY INVISIBLE (-2950 4700);
FORCEPROP 1 LAST PATH I193
J 0
(-3277 4825);
DISPLAY 0.872340 (-3277 4825);
PAINT GREEN (-3277 4825);
DISPLAY INVISIBLE (-3277 4825);
FORCEADD TAP..1
(-3275 4725);
FORCEPROP 3 LASTPIN (-3325 4725) SIG_NAME M_B_CPU0_SA_DQ<21>
J 0
(-3315 4735);
DISPLAY 0.659574 (-3315 4735);
PAINT MONO (-3315 4735);
DISPLAY INVISIBLE (-3315 4735);
FORCEPROP 1 LASTPIN (-3325 4725) BN 21
J 0
(-3337 4733);
DISPLAY 0.489362 (-3337 4733);
PAINT GREEN (-3337 4733);
FORCEPROP 2 LAST CDS_LIB mstr_standard
J 0
(-3275 4725);
DISPLAY 0.723404 (-3275 4725);
PAINT MONO (-3275 4725);
DISPLAY INVISIBLE (-3275 4725);
FORCEPROP 1 LAST BODY_TYPE PLUMBING
J 0
(-3275 4775);
DISPLAY 0.872340 (-3275 4775);
PAINT GREEN (-3275 4775);
DISPLAY INVISIBLE (-3275 4775);
FORCEPROP 1 LAST HDL_TAP TRUE
J 0
(-2950 4600);
DISPLAY 0.872340 (-2950 4600);
DISPLAY INVISIBLE (-2950 4600);
FORCEPROP 1 LAST PATH I194
J 0
(-3277 4725);
DISPLAY 0.872340 (-3277 4725);
PAINT GREEN (-3277 4725);
DISPLAY INVISIBLE (-3277 4725);
FORCEADD TAP..1
(-3275 4675);
FORCEPROP 3 LASTPIN (-3325 4675) SIG_NAME M_B_CPU0_SA_DQ<22>
J 0
(-3315 4685);
DISPLAY 0.659574 (-3315 4685);
PAINT MONO (-3315 4685);
DISPLAY INVISIBLE (-3315 4685);
FORCEPROP 1 LASTPIN (-3325 4675) BN 22
J 0
(-3337 4683);
DISPLAY 0.489362 (-3337 4683);
PAINT GREEN (-3337 4683);
FORCEPROP 2 LAST CDS_LIB mstr_standard
J 0
(-3275 4675);
DISPLAY 0.723404 (-3275 4675);
PAINT MONO (-3275 4675);
DISPLAY INVISIBLE (-3275 4675);
FORCEPROP 1 LAST BODY_TYPE PLUMBING
J 0
(-3275 4725);
DISPLAY 0.872340 (-3275 4725);
PAINT GREEN (-3275 4725);
DISPLAY INVISIBLE (-3275 4725);
FORCEPROP 1 LAST HDL_TAP TRUE
J 0
(-2950 4550);
DISPLAY 0.872340 (-2950 4550);
DISPLAY INVISIBLE (-2950 4550);
FORCEPROP 1 LAST PATH I195
J 0
(-3277 4675);
DISPLAY 0.872340 (-3277 4675);
PAINT GREEN (-3277 4675);
DISPLAY INVISIBLE (-3277 4675);
FORCEADD TAP..1
(-3275 4625);
FORCEPROP 3 LASTPIN (-3325 4625) SIG_NAME M_B_CPU0_SA_DQ<23>
J 0
(-3315 4635);
DISPLAY 0.659574 (-3315 4635);
PAINT MONO (-3315 4635);
DISPLAY INVISIBLE (-3315 4635);
FORCEPROP 1 LASTPIN (-3325 4625) BN 23
J 0
(-3337 4633);
DISPLAY 0.489362 (-3337 4633);
PAINT GREEN (-3337 4633);
FORCEPROP 2 LAST CDS_LIB mstr_standard
J 0
(-3275 4625);
DISPLAY 0.723404 (-3275 4625);
PAINT MONO (-3275 4625);
DISPLAY INVISIBLE (-3275 4625);
FORCEPROP 1 LAST BODY_TYPE PLUMBING
J 0
(-3275 4675);
DISPLAY 0.872340 (-3275 4675);
PAINT GREEN (-3275 4675);
DISPLAY INVISIBLE (-3275 4675);
FORCEPROP 1 LAST HDL_TAP TRUE
J 0
(-2950 4500);
DISPLAY 0.872340 (-2950 4500);
DISPLAY INVISIBLE (-2950 4500);
FORCEPROP 1 LAST PATH I196
J 0
(-3277 4625);
DISPLAY 0.872340 (-3277 4625);
PAINT GREEN (-3277 4625);
DISPLAY INVISIBLE (-3277 4625);
FORCEADD TAP..1
(-3275 4525);
FORCEPROP 3 LASTPIN (-3325 4525) SIG_NAME M_B_CPU0_SA_DQ<24>
J 0
(-3315 4535);
DISPLAY 0.659574 (-3315 4535);
PAINT MONO (-3315 4535);
DISPLAY INVISIBLE (-3315 4535);
FORCEPROP 1 LASTPIN (-3325 4525) BN 24
J 0
(-3337 4533);
DISPLAY 0.489362 (-3337 4533);
PAINT GREEN (-3337 4533);
FORCEPROP 2 LAST CDS_LIB mstr_standard
J 0
(-3275 4525);
DISPLAY 0.723404 (-3275 4525);
PAINT MONO (-3275 4525);
DISPLAY INVISIBLE (-3275 4525);
FORCEPROP 1 LAST BODY_TYPE PLUMBING
J 0
(-3275 4575);
DISPLAY 0.872340 (-3275 4575);
PAINT GREEN (-3275 4575);
DISPLAY INVISIBLE (-3275 4575);
FORCEPROP 1 LAST HDL_TAP TRUE
J 0
(-2950 4400);
DISPLAY 0.872340 (-2950 4400);
DISPLAY INVISIBLE (-2950 4400);
FORCEPROP 1 LAST PATH I197
J 0
(-3277 4525);
DISPLAY 0.872340 (-3277 4525);
PAINT GREEN (-3277 4525);
DISPLAY INVISIBLE (-3277 4525);
FORCEADD TAP..1
(-3275 4475);
FORCEPROP 3 LASTPIN (-3325 4475) SIG_NAME M_B_CPU0_SA_DQ<25>
J 0
(-3315 4485);
DISPLAY 0.659574 (-3315 4485);
PAINT MONO (-3315 4485);
DISPLAY INVISIBLE (-3315 4485);
FORCEPROP 1 LASTPIN (-3325 4475) BN 25
J 0
(-3337 4483);
DISPLAY 0.489362 (-3337 4483);
PAINT GREEN (-3337 4483);
FORCEPROP 2 LAST CDS_LIB mstr_standard
J 0
(-3275 4475);
DISPLAY 0.723404 (-3275 4475);
PAINT MONO (-3275 4475);
DISPLAY INVISIBLE (-3275 4475);
FORCEPROP 1 LAST BODY_TYPE PLUMBING
J 0
(-3275 4525);
DISPLAY 0.872340 (-3275 4525);
PAINT GREEN (-3275 4525);
DISPLAY INVISIBLE (-3275 4525);
FORCEPROP 1 LAST HDL_TAP TRUE
J 0
(-2950 4350);
DISPLAY 0.872340 (-2950 4350);
DISPLAY INVISIBLE (-2950 4350);
FORCEPROP 1 LAST PATH I198
J 0
(-3277 4475);
DISPLAY 0.872340 (-3277 4475);
PAINT GREEN (-3277 4475);
DISPLAY INVISIBLE (-3277 4475);
FORCEADD TAP..1
(-3275 4425);
FORCEPROP 3 LASTPIN (-3325 4425) SIG_NAME M_B_CPU0_SA_DQ<26>
J 0
(-3315 4435);
DISPLAY 0.659574 (-3315 4435);
PAINT MONO (-3315 4435);
DISPLAY INVISIBLE (-3315 4435);
FORCEPROP 1 LASTPIN (-3325 4425) BN 26
J 0
(-3337 4433);
DISPLAY 0.489362 (-3337 4433);
PAINT GREEN (-3337 4433);
FORCEPROP 2 LAST CDS_LIB mstr_standard
J 0
(-3275 4425);
DISPLAY 0.723404 (-3275 4425);
PAINT MONO (-3275 4425);
DISPLAY INVISIBLE (-3275 4425);
FORCEPROP 1 LAST BODY_TYPE PLUMBING
J 0
(-3275 4475);
DISPLAY 0.872340 (-3275 4475);
PAINT GREEN (-3275 4475);
DISPLAY INVISIBLE (-3275 4475);
FORCEPROP 1 LAST HDL_TAP TRUE
J 0
(-2950 4300);
DISPLAY 0.872340 (-2950 4300);
DISPLAY INVISIBLE (-2950 4300);
FORCEPROP 1 LAST PATH I199
J 0
(-3277 4425);
DISPLAY 0.872340 (-3277 4425);
PAINT GREEN (-3277 4425);
DISPLAY INVISIBLE (-3277 4425);
FORCEADD TAP..1
(-3275 4375);
FORCEPROP 3 LASTPIN (-3325 4375) SIG_NAME M_B_CPU0_SA_DQ<27>
J 0
(-3315 4385);
DISPLAY 0.659574 (-3315 4385);
PAINT MONO (-3315 4385);
DISPLAY INVISIBLE (-3315 4385);
FORCEPROP 1 LASTPIN (-3325 4375) BN 27
J 0
(-3337 4383);
DISPLAY 0.489362 (-3337 4383);
PAINT GREEN (-3337 4383);
FORCEPROP 2 LAST CDS_LIB mstr_standard
J 0
(-3275 4375);
DISPLAY 0.723404 (-3275 4375);
PAINT MONO (-3275 4375);
DISPLAY INVISIBLE (-3275 4375);
FORCEPROP 1 LAST BODY_TYPE PLUMBING
J 0
(-3275 4425);
DISPLAY 0.872340 (-3275 4425);
PAINT GREEN (-3275 4425);
DISPLAY INVISIBLE (-3275 4425);
FORCEPROP 1 LAST HDL_TAP TRUE
J 0
(-2950 4250);
DISPLAY 0.872340 (-2950 4250);
DISPLAY INVISIBLE (-2950 4250);
FORCEPROP 1 LAST PATH I200
J 0
(-3277 4375);
DISPLAY 0.872340 (-3277 4375);
PAINT GREEN (-3277 4375);
DISPLAY INVISIBLE (-3277 4375);
FORCEADD TAP..1
(-3275 4275);
FORCEPROP 3 LASTPIN (-3325 4275) SIG_NAME M_B_CPU0_SA_DQ<29>
J 0
(-3315 4285);
DISPLAY 0.659574 (-3315 4285);
PAINT MONO (-3315 4285);
DISPLAY INVISIBLE (-3315 4285);
FORCEPROP 1 LASTPIN (-3325 4275) BN 29
J 0
(-3337 4283);
DISPLAY 0.489362 (-3337 4283);
PAINT GREEN (-3337 4283);
FORCEPROP 2 LAST CDS_LIB mstr_standard
J 0
(-3275 4275);
DISPLAY 0.723404 (-3275 4275);
PAINT MONO (-3275 4275);
DISPLAY INVISIBLE (-3275 4275);
FORCEPROP 1 LAST BODY_TYPE PLUMBING
J 0
(-3275 4325);
DISPLAY 0.872340 (-3275 4325);
PAINT GREEN (-3275 4325);
DISPLAY INVISIBLE (-3275 4325);
FORCEPROP 1 LAST HDL_TAP TRUE
J 0
(-2950 4150);
DISPLAY 0.872340 (-2950 4150);
DISPLAY INVISIBLE (-2950 4150);
FORCEPROP 1 LAST PATH I201
J 0
(-3277 4275);
DISPLAY 0.872340 (-3277 4275);
PAINT GREEN (-3277 4275);
DISPLAY INVISIBLE (-3277 4275);
FORCEADD TAP..1
(-3275 4225);
FORCEPROP 3 LASTPIN (-3325 4225) SIG_NAME M_B_CPU0_SA_DQ<30>
J 0
(-3315 4235);
DISPLAY 0.659574 (-3315 4235);
PAINT MONO (-3315 4235);
DISPLAY INVISIBLE (-3315 4235);
FORCEPROP 1 LASTPIN (-3325 4225) BN 30
J 0
(-3337 4233);
DISPLAY 0.489362 (-3337 4233);
PAINT GREEN (-3337 4233);
FORCEPROP 2 LAST CDS_LIB mstr_standard
J 0
(-3275 4225);
DISPLAY 0.723404 (-3275 4225);
PAINT MONO (-3275 4225);
DISPLAY INVISIBLE (-3275 4225);
FORCEPROP 1 LAST BODY_TYPE PLUMBING
J 0
(-3275 4275);
DISPLAY 0.872340 (-3275 4275);
PAINT GREEN (-3275 4275);
DISPLAY INVISIBLE (-3275 4275);
FORCEPROP 1 LAST HDL_TAP TRUE
J 0
(-2950 4100);
DISPLAY 0.872340 (-2950 4100);
DISPLAY INVISIBLE (-2950 4100);
FORCEPROP 1 LAST PATH I202
J 0
(-3277 4225);
DISPLAY 0.872340 (-3277 4225);
PAINT GREEN (-3277 4225);
DISPLAY INVISIBLE (-3277 4225);
FORCEADD TAP..1
(-3275 4325);
FORCEPROP 3 LASTPIN (-3325 4325) SIG_NAME M_B_CPU0_SA_DQ<28>
J 0
(-3315 4335);
DISPLAY 0.659574 (-3315 4335);
PAINT MONO (-3315 4335);
DISPLAY INVISIBLE (-3315 4335);
FORCEPROP 1 LASTPIN (-3325 4325) BN 28
J 0
(-3337 4333);
DISPLAY 0.489362 (-3337 4333);
PAINT GREEN (-3337 4333);
FORCEPROP 2 LAST CDS_LIB mstr_standard
J 0
(-3275 4325);
DISPLAY 0.723404 (-3275 4325);
PAINT MONO (-3275 4325);
DISPLAY INVISIBLE (-3275 4325);
FORCEPROP 1 LAST BODY_TYPE PLUMBING
J 0
(-3275 4375);
DISPLAY 0.872340 (-3275 4375);
PAINT GREEN (-3275 4375);
DISPLAY INVISIBLE (-3275 4375);
FORCEPROP 1 LAST HDL_TAP TRUE
J 0
(-2950 4200);
DISPLAY 0.872340 (-2950 4200);
DISPLAY INVISIBLE (-2950 4200);
FORCEPROP 1 LAST PATH I203
J 0
(-3277 4325);
DISPLAY 0.872340 (-3277 4325);
PAINT GREEN (-3277 4325);
DISPLAY INVISIBLE (-3277 4325);
FORCEADD TAP..1
(-3275 4175);
FORCEPROP 3 LASTPIN (-3325 4175) SIG_NAME M_B_CPU0_SA_DQ<31>
J 0
(-3315 4185);
DISPLAY 0.659574 (-3315 4185);
PAINT MONO (-3315 4185);
DISPLAY INVISIBLE (-3315 4185);
FORCEPROP 1 LASTPIN (-3325 4175) BN 31
J 0
(-3337 4183);
DISPLAY 0.489362 (-3337 4183);
PAINT GREEN (-3337 4183);
FORCEPROP 2 LAST CDS_LIB mstr_standard
J 0
(-3275 4175);
DISPLAY 0.723404 (-3275 4175);
PAINT MONO (-3275 4175);
DISPLAY INVISIBLE (-3275 4175);
FORCEPROP 1 LAST BODY_TYPE PLUMBING
J 0
(-3275 4225);
DISPLAY 0.872340 (-3275 4225);
PAINT GREEN (-3275 4225);
DISPLAY INVISIBLE (-3275 4225);
FORCEPROP 1 LAST HDL_TAP TRUE
J 0
(-2950 4050);
DISPLAY 0.872340 (-2950 4050);
DISPLAY INVISIBLE (-2950 4050);
FORCEPROP 1 LAST PATH I204
J 0
(-3277 4175);
DISPLAY 0.872340 (-3277 4175);
PAINT GREEN (-3277 4175);
DISPLAY INVISIBLE (-3277 4175);
FORCEADD OFFPAGE..3
(-2550 4100);
FORCEPROP 2 LAST $XR0 86 
J 0
(-2336 4100);
DISPLAY 0.638298 (-2336 4100);
PAINT MONO (-2336 4100);
FORCEPROP 2 LAST PATH I205
J 0
(-2325 4150);
DISPLAY 1.021277 (-2325 4150);
DISPLAY INVISIBLE (-2325 4150);
FORCEPROP 1 LAST COMMENT_BODY TRUE
J 0
(-2600 4000);
DISPLAY 0.872340 (-2600 4000);
PAINT GREEN (-2600 4000);
DISPLAY INVISIBLE (-2600 4000);
FORCEPROP 1 LAST OFFPAGE TRUE
J 0
(-2225 3975);
DISPLAY 0.872340 (-2225 3975);
PAINT GREEN (-2225 3975);
DISPLAY INVISIBLE (-2225 3975);
FORCEPROP 2 LAST CDS_LIB mstr_standard
J 0
(-2550 4100);
DISPLAY 0.723404 (-2550 4100);
PAINT MONO (-2550 4100);
DISPLAY INVISIBLE (-2550 4100);
FORCEADD OFFPAGE..6
R 2
(-2675 2325);
FORCEPROP 2 LAST $XR0 86 
J 0
(-2461 2325);
DISPLAY 0.638298 (-2461 2325);
PAINT MONO (-2461 2325);
FORCEPROP 2 LAST PATH I206
J 0
(-2450 2375);
DISPLAY 1.021277 (-2450 2375);
DISPLAY INVISIBLE (-2450 2375);
FORCEPROP 1 LAST COMMENT_BODY TRUE
J 2
(-2775 2250);
DISPLAY 0.872340 (-2775 2250);
PAINT GREEN (-2775 2250);
DISPLAY INVISIBLE (-2775 2250);
FORCEPROP 1 LAST OFFPAGE TRUE
J 2
(-3000 2200);
DISPLAY 0.872340 (-3000 2200);
PAINT GREEN (-3000 2200);
DISPLAY INVISIBLE (-3000 2200);
FORCEPROP 2 LAST CDS_LIB mstr_standard
J 2
(-2675 2325);
DISPLAY 0.723404 (-2675 2325);
PAINT MONO (-2675 2325);
DISPLAY INVISIBLE (-2675 2325);
FORCEADD TAP..1
(-3275 3975);
FORCEPROP 3 LASTPIN (-3325 3975) SIG_NAME M_B_CPU0_SB_DQ<2>
J 0
(-3315 3985);
DISPLAY 0.659574 (-3315 3985);
PAINT MONO (-3315 3985);
DISPLAY INVISIBLE (-3315 3985);
FORCEPROP 1 LASTPIN (-3325 3975) BN 2
J 0
(-3337 3983);
DISPLAY 0.489362 (-3337 3983);
PAINT GREEN (-3337 3983);
FORCEPROP 2 LAST CDS_LIB mstr_standard
J 0
(-3275 3975);
DISPLAY 0.723404 (-3275 3975);
PAINT MONO (-3275 3975);
DISPLAY INVISIBLE (-3275 3975);
FORCEPROP 1 LAST BODY_TYPE PLUMBING
J 0
(-3275 4025);
DISPLAY 0.872340 (-3275 4025);
PAINT GREEN (-3275 4025);
DISPLAY INVISIBLE (-3275 4025);
FORCEPROP 1 LAST HDL_TAP TRUE
J 0
(-2950 3850);
DISPLAY 0.872340 (-2950 3850);
DISPLAY INVISIBLE (-2950 3850);
FORCEPROP 1 LAST PATH I207
J 0
(-3277 3975);
DISPLAY 0.872340 (-3277 3975);
PAINT GREEN (-3277 3975);
DISPLAY INVISIBLE (-3277 3975);
FORCEADD TAP..1
(-3275 4025);
FORCEPROP 3 LASTPIN (-3325 4025) SIG_NAME M_B_CPU0_SB_DQ<1>
J 0
(-3315 4035);
DISPLAY 0.659574 (-3315 4035);
PAINT MONO (-3315 4035);
DISPLAY INVISIBLE (-3315 4035);
FORCEPROP 1 LASTPIN (-3325 4025) BN 1
J 0
(-3337 4033);
DISPLAY 0.489362 (-3337 4033);
PAINT GREEN (-3337 4033);
FORCEPROP 2 LAST CDS_LIB mstr_standard
J 0
(-3275 4025);
DISPLAY 0.723404 (-3275 4025);
PAINT MONO (-3275 4025);
DISPLAY INVISIBLE (-3275 4025);
FORCEPROP 1 LAST BODY_TYPE PLUMBING
J 0
(-3275 4075);
DISPLAY 0.872340 (-3275 4075);
PAINT GREEN (-3275 4075);
DISPLAY INVISIBLE (-3275 4075);
FORCEPROP 1 LAST HDL_TAP TRUE
J 0
(-2950 3900);
DISPLAY 0.872340 (-2950 3900);
DISPLAY INVISIBLE (-2950 3900);
FORCEPROP 1 LAST PATH I208
J 0
(-3277 4025);
DISPLAY 0.872340 (-3277 4025);
PAINT GREEN (-3277 4025);
DISPLAY INVISIBLE (-3277 4025);
FORCEADD TAP..1
(-3275 4075);
FORCEPROP 3 LASTPIN (-3325 4075) SIG_NAME M_B_CPU0_SB_DQ<0>
J 0
(-3315 4085);
DISPLAY 0.659574 (-3315 4085);
PAINT MONO (-3315 4085);
DISPLAY INVISIBLE (-3315 4085);
FORCEPROP 1 LASTPIN (-3325 4075) BN 0
J 0
(-3337 4083);
DISPLAY 0.489362 (-3337 4083);
PAINT GREEN (-3337 4083);
FORCEPROP 2 LAST CDS_LIB mstr_standard
J 0
(-3275 4075);
DISPLAY 0.723404 (-3275 4075);
PAINT MONO (-3275 4075);
DISPLAY INVISIBLE (-3275 4075);
FORCEPROP 1 LAST BODY_TYPE PLUMBING
J 0
(-3275 4125);
DISPLAY 0.872340 (-3275 4125);
PAINT GREEN (-3275 4125);
DISPLAY INVISIBLE (-3275 4125);
FORCEPROP 1 LAST HDL_TAP TRUE
J 0
(-2950 3950);
DISPLAY 0.872340 (-2950 3950);
DISPLAY INVISIBLE (-2950 3950);
FORCEPROP 1 LAST PATH I209
J 0
(-3277 4075);
DISPLAY 0.872340 (-3277 4075);
PAINT GREEN (-3277 4075);
DISPLAY INVISIBLE (-3277 4075);
FORCEADD TAP..1
(-3275 3925);
FORCEPROP 3 LASTPIN (-3325 3925) SIG_NAME M_B_CPU0_SB_DQ<3>
J 0
(-3315 3935);
DISPLAY 0.659574 (-3315 3935);
PAINT MONO (-3315 3935);
DISPLAY INVISIBLE (-3315 3935);
FORCEPROP 1 LASTPIN (-3325 3925) BN 3
J 0
(-3337 3933);
DISPLAY 0.489362 (-3337 3933);
PAINT GREEN (-3337 3933);
FORCEPROP 2 LAST CDS_LIB mstr_standard
J 0
(-3275 3925);
DISPLAY 0.723404 (-3275 3925);
PAINT MONO (-3275 3925);
DISPLAY INVISIBLE (-3275 3925);
FORCEPROP 1 LAST BODY_TYPE PLUMBING
J 0
(-3275 3975);
DISPLAY 0.872340 (-3275 3975);
PAINT GREEN (-3275 3975);
DISPLAY INVISIBLE (-3275 3975);
FORCEPROP 1 LAST HDL_TAP TRUE
J 0
(-2950 3800);
DISPLAY 0.872340 (-2950 3800);
DISPLAY INVISIBLE (-2950 3800);
FORCEPROP 1 LAST PATH I210
J 0
(-3277 3925);
DISPLAY 0.872340 (-3277 3925);
PAINT GREEN (-3277 3925);
DISPLAY INVISIBLE (-3277 3925);
FORCEADD TAP..1
(-3275 3875);
FORCEPROP 3 LASTPIN (-3325 3875) SIG_NAME M_B_CPU0_SB_DQ<4>
J 0
(-3315 3885);
DISPLAY 0.659574 (-3315 3885);
PAINT MONO (-3315 3885);
DISPLAY INVISIBLE (-3315 3885);
FORCEPROP 1 LASTPIN (-3325 3875) BN 4
J 0
(-3337 3883);
DISPLAY 0.489362 (-3337 3883);
PAINT GREEN (-3337 3883);
FORCEPROP 2 LAST CDS_LIB mstr_standard
J 0
(-3275 3875);
DISPLAY 0.723404 (-3275 3875);
PAINT MONO (-3275 3875);
DISPLAY INVISIBLE (-3275 3875);
FORCEPROP 1 LAST BODY_TYPE PLUMBING
J 0
(-3275 3925);
DISPLAY 0.872340 (-3275 3925);
PAINT GREEN (-3275 3925);
DISPLAY INVISIBLE (-3275 3925);
FORCEPROP 1 LAST HDL_TAP TRUE
J 0
(-2950 3750);
DISPLAY 0.872340 (-2950 3750);
DISPLAY INVISIBLE (-2950 3750);
FORCEPROP 1 LAST PATH I211
J 0
(-3277 3875);
DISPLAY 0.872340 (-3277 3875);
PAINT GREEN (-3277 3875);
DISPLAY INVISIBLE (-3277 3875);
FORCEADD TAP..1
(-3275 3825);
FORCEPROP 3 LASTPIN (-3325 3825) SIG_NAME M_B_CPU0_SB_DQ<5>
J 0
(-3315 3835);
DISPLAY 0.659574 (-3315 3835);
PAINT MONO (-3315 3835);
DISPLAY INVISIBLE (-3315 3835);
FORCEPROP 1 LASTPIN (-3325 3825) BN 5
J 0
(-3337 3833);
DISPLAY 0.489362 (-3337 3833);
PAINT GREEN (-3337 3833);
FORCEPROP 2 LAST CDS_LIB mstr_standard
J 0
(-3275 3825);
DISPLAY 0.723404 (-3275 3825);
PAINT MONO (-3275 3825);
DISPLAY INVISIBLE (-3275 3825);
FORCEPROP 1 LAST BODY_TYPE PLUMBING
J 0
(-3275 3875);
DISPLAY 0.872340 (-3275 3875);
PAINT GREEN (-3275 3875);
DISPLAY INVISIBLE (-3275 3875);
FORCEPROP 1 LAST HDL_TAP TRUE
J 0
(-2950 3700);
DISPLAY 0.872340 (-2950 3700);
DISPLAY INVISIBLE (-2950 3700);
FORCEPROP 1 LAST PATH I212
J 0
(-3277 3825);
DISPLAY 0.872340 (-3277 3825);
PAINT GREEN (-3277 3825);
DISPLAY INVISIBLE (-3277 3825);
FORCEADD TAP..1
(-3275 3725);
FORCEPROP 3 LASTPIN (-3325 3725) SIG_NAME M_B_CPU0_SB_DQ<7>
J 0
(-3315 3735);
DISPLAY 0.659574 (-3315 3735);
PAINT MONO (-3315 3735);
DISPLAY INVISIBLE (-3315 3735);
FORCEPROP 1 LASTPIN (-3325 3725) BN 7
J 0
(-3337 3733);
DISPLAY 0.489362 (-3337 3733);
PAINT GREEN (-3337 3733);
FORCEPROP 2 LAST CDS_LIB mstr_standard
J 0
(-3275 3725);
DISPLAY 0.723404 (-3275 3725);
PAINT MONO (-3275 3725);
DISPLAY INVISIBLE (-3275 3725);
FORCEPROP 1 LAST BODY_TYPE PLUMBING
J 0
(-3275 3775);
DISPLAY 0.872340 (-3275 3775);
PAINT GREEN (-3275 3775);
DISPLAY INVISIBLE (-3275 3775);
FORCEPROP 1 LAST HDL_TAP TRUE
J 0
(-2950 3600);
DISPLAY 0.872340 (-2950 3600);
DISPLAY INVISIBLE (-2950 3600);
FORCEPROP 1 LAST PATH I213
J 0
(-3277 3725);
DISPLAY 0.872340 (-3277 3725);
PAINT GREEN (-3277 3725);
DISPLAY INVISIBLE (-3277 3725);
FORCEADD TAP..1
(-3275 3775);
FORCEPROP 3 LASTPIN (-3325 3775) SIG_NAME M_B_CPU0_SB_DQ<6>
J 0
(-3315 3785);
DISPLAY 0.659574 (-3315 3785);
PAINT MONO (-3315 3785);
DISPLAY INVISIBLE (-3315 3785);
FORCEPROP 1 LASTPIN (-3325 3775) BN 6
J 0
(-3337 3783);
DISPLAY 0.489362 (-3337 3783);
PAINT GREEN (-3337 3783);
FORCEPROP 2 LAST CDS_LIB mstr_standard
J 0
(-3275 3775);
DISPLAY 0.723404 (-3275 3775);
PAINT MONO (-3275 3775);
DISPLAY INVISIBLE (-3275 3775);
FORCEPROP 1 LAST BODY_TYPE PLUMBING
J 0
(-3275 3825);
DISPLAY 0.872340 (-3275 3825);
PAINT GREEN (-3275 3825);
DISPLAY INVISIBLE (-3275 3825);
FORCEPROP 1 LAST HDL_TAP TRUE
J 0
(-2950 3650);
DISPLAY 0.872340 (-2950 3650);
DISPLAY INVISIBLE (-2950 3650);
FORCEPROP 1 LAST PATH I214
J 0
(-3277 3775);
DISPLAY 0.872340 (-3277 3775);
PAINT GREEN (-3277 3775);
DISPLAY INVISIBLE (-3277 3775);
FORCEADD TAP..1
(-3275 3625);
FORCEPROP 3 LASTPIN (-3325 3625) SIG_NAME M_B_CPU0_SB_DQ<8>
J 0
(-3315 3635);
DISPLAY 0.659574 (-3315 3635);
PAINT MONO (-3315 3635);
DISPLAY INVISIBLE (-3315 3635);
FORCEPROP 1 LASTPIN (-3325 3625) BN 8
J 0
(-3337 3633);
DISPLAY 0.489362 (-3337 3633);
PAINT GREEN (-3337 3633);
FORCEPROP 2 LAST CDS_LIB mstr_standard
J 0
(-3275 3625);
DISPLAY 0.723404 (-3275 3625);
PAINT MONO (-3275 3625);
DISPLAY INVISIBLE (-3275 3625);
FORCEPROP 1 LAST BODY_TYPE PLUMBING
J 0
(-3275 3675);
DISPLAY 0.872340 (-3275 3675);
PAINT GREEN (-3275 3675);
DISPLAY INVISIBLE (-3275 3675);
FORCEPROP 1 LAST HDL_TAP TRUE
J 0
(-2950 3500);
DISPLAY 0.872340 (-2950 3500);
DISPLAY INVISIBLE (-2950 3500);
FORCEPROP 1 LAST PATH I215
J 0
(-3277 3625);
DISPLAY 0.872340 (-3277 3625);
PAINT GREEN (-3277 3625);
DISPLAY INVISIBLE (-3277 3625);
FORCEADD TAP..1
(-3275 3475);
FORCEPROP 3 LASTPIN (-3325 3475) SIG_NAME M_B_CPU0_SB_DQ<11>
J 0
(-3315 3485);
DISPLAY 0.659574 (-3315 3485);
PAINT MONO (-3315 3485);
DISPLAY INVISIBLE (-3315 3485);
FORCEPROP 1 LASTPIN (-3325 3475) BN 11
J 0
(-3337 3483);
DISPLAY 0.489362 (-3337 3483);
PAINT GREEN (-3337 3483);
FORCEPROP 2 LAST CDS_LIB mstr_standard
J 0
(-3275 3475);
DISPLAY 0.723404 (-3275 3475);
PAINT MONO (-3275 3475);
DISPLAY INVISIBLE (-3275 3475);
FORCEPROP 1 LAST BODY_TYPE PLUMBING
J 0
(-3275 3525);
DISPLAY 0.872340 (-3275 3525);
PAINT GREEN (-3275 3525);
DISPLAY INVISIBLE (-3275 3525);
FORCEPROP 1 LAST HDL_TAP TRUE
J 0
(-2950 3350);
DISPLAY 0.872340 (-2950 3350);
DISPLAY INVISIBLE (-2950 3350);
FORCEPROP 1 LAST PATH I216
J 0
(-3277 3475);
DISPLAY 0.872340 (-3277 3475);
PAINT GREEN (-3277 3475);
DISPLAY INVISIBLE (-3277 3475);
FORCEADD TAP..1
(-3275 3575);
FORCEPROP 3 LASTPIN (-3325 3575) SIG_NAME M_B_CPU0_SB_DQ<9>
J 0
(-3315 3585);
DISPLAY 0.659574 (-3315 3585);
PAINT MONO (-3315 3585);
DISPLAY INVISIBLE (-3315 3585);
FORCEPROP 1 LASTPIN (-3325 3575) BN 9
J 0
(-3337 3583);
DISPLAY 0.489362 (-3337 3583);
PAINT GREEN (-3337 3583);
FORCEPROP 2 LAST CDS_LIB mstr_standard
J 0
(-3275 3575);
DISPLAY 0.723404 (-3275 3575);
PAINT MONO (-3275 3575);
DISPLAY INVISIBLE (-3275 3575);
FORCEPROP 1 LAST BODY_TYPE PLUMBING
J 0
(-3275 3625);
DISPLAY 0.872340 (-3275 3625);
PAINT GREEN (-3275 3625);
DISPLAY INVISIBLE (-3275 3625);
FORCEPROP 1 LAST HDL_TAP TRUE
J 0
(-2950 3450);
DISPLAY 0.872340 (-2950 3450);
DISPLAY INVISIBLE (-2950 3450);
FORCEPROP 1 LAST PATH I217
J 0
(-3277 3575);
DISPLAY 0.872340 (-3277 3575);
PAINT GREEN (-3277 3575);
DISPLAY INVISIBLE (-3277 3575);
FORCEADD TAP..1
(-3275 3525);
FORCEPROP 3 LASTPIN (-3325 3525) SIG_NAME M_B_CPU0_SB_DQ<10>
J 0
(-3315 3535);
DISPLAY 0.659574 (-3315 3535);
PAINT MONO (-3315 3535);
DISPLAY INVISIBLE (-3315 3535);
FORCEPROP 1 LASTPIN (-3325 3525) BN 10
J 0
(-3337 3533);
DISPLAY 0.489362 (-3337 3533);
PAINT GREEN (-3337 3533);
FORCEPROP 2 LAST CDS_LIB mstr_standard
J 0
(-3275 3525);
DISPLAY 0.723404 (-3275 3525);
PAINT MONO (-3275 3525);
DISPLAY INVISIBLE (-3275 3525);
FORCEPROP 1 LAST BODY_TYPE PLUMBING
J 0
(-3275 3575);
DISPLAY 0.872340 (-3275 3575);
PAINT GREEN (-3275 3575);
DISPLAY INVISIBLE (-3275 3575);
FORCEPROP 1 LAST HDL_TAP TRUE
J 0
(-2950 3400);
DISPLAY 0.872340 (-2950 3400);
DISPLAY INVISIBLE (-2950 3400);
FORCEPROP 1 LAST PATH I218
J 0
(-3277 3525);
DISPLAY 0.872340 (-3277 3525);
PAINT GREEN (-3277 3525);
DISPLAY INVISIBLE (-3277 3525);
FORCEADD TAP..1
(-3275 3425);
FORCEPROP 3 LASTPIN (-3325 3425) SIG_NAME M_B_CPU0_SB_DQ<12>
J 0
(-3315 3435);
DISPLAY 0.659574 (-3315 3435);
PAINT MONO (-3315 3435);
DISPLAY INVISIBLE (-3315 3435);
FORCEPROP 1 LASTPIN (-3325 3425) BN 12
J 0
(-3337 3433);
DISPLAY 0.489362 (-3337 3433);
PAINT GREEN (-3337 3433);
FORCEPROP 2 LAST CDS_LIB mstr_standard
J 0
(-3275 3425);
DISPLAY 0.723404 (-3275 3425);
PAINT MONO (-3275 3425);
DISPLAY INVISIBLE (-3275 3425);
FORCEPROP 1 LAST BODY_TYPE PLUMBING
J 0
(-3275 3475);
DISPLAY 0.872340 (-3275 3475);
PAINT GREEN (-3275 3475);
DISPLAY INVISIBLE (-3275 3475);
FORCEPROP 1 LAST HDL_TAP TRUE
J 0
(-2950 3300);
DISPLAY 0.872340 (-2950 3300);
DISPLAY INVISIBLE (-2950 3300);
FORCEPROP 1 LAST PATH I219
J 0
(-3277 3425);
DISPLAY 0.872340 (-3277 3425);
PAINT GREEN (-3277 3425);
DISPLAY INVISIBLE (-3277 3425);
FORCEADD TAP..1
(-3275 3375);
FORCEPROP 3 LASTPIN (-3325 3375) SIG_NAME M_B_CPU0_SB_DQ<13>
J 0
(-3315 3385);
DISPLAY 0.659574 (-3315 3385);
PAINT MONO (-3315 3385);
DISPLAY INVISIBLE (-3315 3385);
FORCEPROP 1 LASTPIN (-3325 3375) BN 13
J 0
(-3337 3383);
DISPLAY 0.489362 (-3337 3383);
PAINT GREEN (-3337 3383);
FORCEPROP 2 LAST CDS_LIB mstr_standard
J 0
(-3275 3375);
DISPLAY 0.723404 (-3275 3375);
PAINT MONO (-3275 3375);
DISPLAY INVISIBLE (-3275 3375);
FORCEPROP 1 LAST BODY_TYPE PLUMBING
J 0
(-3275 3425);
DISPLAY 0.872340 (-3275 3425);
PAINT GREEN (-3275 3425);
DISPLAY INVISIBLE (-3275 3425);
FORCEPROP 1 LAST HDL_TAP TRUE
J 0
(-2950 3250);
DISPLAY 0.872340 (-2950 3250);
DISPLAY INVISIBLE (-2950 3250);
FORCEPROP 1 LAST PATH I220
J 0
(-3277 3375);
DISPLAY 0.872340 (-3277 3375);
PAINT GREEN (-3277 3375);
DISPLAY INVISIBLE (-3277 3375);
FORCEADD TAP..1
(-3275 3275);
FORCEPROP 3 LASTPIN (-3325 3275) SIG_NAME M_B_CPU0_SB_DQ<15>
J 0
(-3315 3285);
DISPLAY 0.659574 (-3315 3285);
PAINT MONO (-3315 3285);
DISPLAY INVISIBLE (-3315 3285);
FORCEPROP 1 LASTPIN (-3325 3275) BN 15
J 0
(-3337 3283);
DISPLAY 0.489362 (-3337 3283);
PAINT GREEN (-3337 3283);
FORCEPROP 2 LAST CDS_LIB mstr_standard
J 0
(-3275 3275);
DISPLAY 0.723404 (-3275 3275);
PAINT MONO (-3275 3275);
DISPLAY INVISIBLE (-3275 3275);
FORCEPROP 1 LAST BODY_TYPE PLUMBING
J 0
(-3275 3325);
DISPLAY 0.872340 (-3275 3325);
PAINT GREEN (-3275 3325);
DISPLAY INVISIBLE (-3275 3325);
FORCEPROP 1 LAST HDL_TAP TRUE
J 0
(-2950 3150);
DISPLAY 0.872340 (-2950 3150);
DISPLAY INVISIBLE (-2950 3150);
FORCEPROP 1 LAST PATH I221
J 0
(-3277 3275);
DISPLAY 0.872340 (-3277 3275);
PAINT GREEN (-3277 3275);
DISPLAY INVISIBLE (-3277 3275);
FORCEADD TAP..1
(-3275 3325);
FORCEPROP 3 LASTPIN (-3325 3325) SIG_NAME M_B_CPU0_SB_DQ<14>
J 0
(-3315 3335);
DISPLAY 0.659574 (-3315 3335);
PAINT MONO (-3315 3335);
DISPLAY INVISIBLE (-3315 3335);
FORCEPROP 1 LASTPIN (-3325 3325) BN 14
J 0
(-3337 3333);
DISPLAY 0.489362 (-3337 3333);
PAINT GREEN (-3337 3333);
FORCEPROP 2 LAST CDS_LIB mstr_standard
J 0
(-3275 3325);
DISPLAY 0.723404 (-3275 3325);
PAINT MONO (-3275 3325);
DISPLAY INVISIBLE (-3275 3325);
FORCEPROP 1 LAST BODY_TYPE PLUMBING
J 0
(-3275 3375);
DISPLAY 0.872340 (-3275 3375);
PAINT GREEN (-3275 3375);
DISPLAY INVISIBLE (-3275 3375);
FORCEPROP 1 LAST HDL_TAP TRUE
J 0
(-2950 3200);
DISPLAY 0.872340 (-2950 3200);
DISPLAY INVISIBLE (-2950 3200);
FORCEPROP 1 LAST PATH I222
J 0
(-3277 3325);
DISPLAY 0.872340 (-3277 3325);
PAINT GREEN (-3277 3325);
DISPLAY INVISIBLE (-3277 3325);
FORCEADD TAP..1
(-3275 3175);
FORCEPROP 3 LASTPIN (-3325 3175) SIG_NAME M_B_CPU0_SB_DQ<16>
J 0
(-3315 3185);
DISPLAY 0.659574 (-3315 3185);
PAINT MONO (-3315 3185);
DISPLAY INVISIBLE (-3315 3185);
FORCEPROP 1 LASTPIN (-3325 3175) BN 16
J 0
(-3337 3183);
DISPLAY 0.489362 (-3337 3183);
PAINT GREEN (-3337 3183);
FORCEPROP 2 LAST CDS_LIB mstr_standard
J 0
(-3275 3175);
DISPLAY 0.723404 (-3275 3175);
PAINT MONO (-3275 3175);
DISPLAY INVISIBLE (-3275 3175);
FORCEPROP 1 LAST BODY_TYPE PLUMBING
J 0
(-3275 3225);
DISPLAY 0.872340 (-3275 3225);
PAINT GREEN (-3275 3225);
DISPLAY INVISIBLE (-3275 3225);
FORCEPROP 1 LAST HDL_TAP TRUE
J 0
(-2950 3050);
DISPLAY 0.872340 (-2950 3050);
DISPLAY INVISIBLE (-2950 3050);
FORCEPROP 1 LAST PATH I223
J 0
(-3277 3175);
DISPLAY 0.872340 (-3277 3175);
PAINT GREEN (-3277 3175);
DISPLAY INVISIBLE (-3277 3175);
FORCEADD TAP..1
(-3275 3125);
FORCEPROP 3 LASTPIN (-3325 3125) SIG_NAME M_B_CPU0_SB_DQ<17>
J 0
(-3315 3135);
DISPLAY 0.659574 (-3315 3135);
PAINT MONO (-3315 3135);
DISPLAY INVISIBLE (-3315 3135);
FORCEPROP 1 LASTPIN (-3325 3125) BN 17
J 0
(-3337 3133);
DISPLAY 0.489362 (-3337 3133);
PAINT GREEN (-3337 3133);
FORCEPROP 2 LAST CDS_LIB mstr_standard
J 0
(-3275 3125);
DISPLAY 0.723404 (-3275 3125);
PAINT MONO (-3275 3125);
DISPLAY INVISIBLE (-3275 3125);
FORCEPROP 1 LAST BODY_TYPE PLUMBING
J 0
(-3275 3175);
DISPLAY 0.872340 (-3275 3175);
PAINT GREEN (-3275 3175);
DISPLAY INVISIBLE (-3275 3175);
FORCEPROP 1 LAST HDL_TAP TRUE
J 0
(-2950 3000);
DISPLAY 0.872340 (-2950 3000);
DISPLAY INVISIBLE (-2950 3000);
FORCEPROP 1 LAST PATH I224
J 0
(-3277 3125);
DISPLAY 0.872340 (-3277 3125);
PAINT GREEN (-3277 3125);
DISPLAY INVISIBLE (-3277 3125);
FORCEADD TAP..1
(-3275 3075);
FORCEPROP 3 LASTPIN (-3325 3075) SIG_NAME M_B_CPU0_SB_DQ<18>
J 0
(-3315 3085);
DISPLAY 0.659574 (-3315 3085);
PAINT MONO (-3315 3085);
DISPLAY INVISIBLE (-3315 3085);
FORCEPROP 1 LASTPIN (-3325 3075) BN 18
J 0
(-3337 3083);
DISPLAY 0.489362 (-3337 3083);
PAINT GREEN (-3337 3083);
FORCEPROP 2 LAST CDS_LIB mstr_standard
J 0
(-3275 3075);
DISPLAY 0.723404 (-3275 3075);
PAINT MONO (-3275 3075);
DISPLAY INVISIBLE (-3275 3075);
FORCEPROP 1 LAST BODY_TYPE PLUMBING
J 0
(-3275 3125);
DISPLAY 0.872340 (-3275 3125);
PAINT GREEN (-3275 3125);
DISPLAY INVISIBLE (-3275 3125);
FORCEPROP 1 LAST HDL_TAP TRUE
J 0
(-2950 2950);
DISPLAY 0.872340 (-2950 2950);
DISPLAY INVISIBLE (-2950 2950);
FORCEPROP 1 LAST PATH I225
J 0
(-3277 3075);
DISPLAY 0.872340 (-3277 3075);
PAINT GREEN (-3277 3075);
DISPLAY INVISIBLE (-3277 3075);
FORCEADD TAP..1
(-3275 2975);
FORCEPROP 3 LASTPIN (-3325 2975) SIG_NAME M_B_CPU0_SB_DQ<20>
J 0
(-3315 2985);
DISPLAY 0.659574 (-3315 2985);
PAINT MONO (-3315 2985);
DISPLAY INVISIBLE (-3315 2985);
FORCEPROP 1 LASTPIN (-3325 2975) BN 20
J 0
(-3337 2983);
DISPLAY 0.489362 (-3337 2983);
PAINT GREEN (-3337 2983);
FORCEPROP 2 LAST CDS_LIB mstr_standard
J 0
(-3275 2975);
DISPLAY 0.723404 (-3275 2975);
PAINT MONO (-3275 2975);
DISPLAY INVISIBLE (-3275 2975);
FORCEPROP 1 LAST BODY_TYPE PLUMBING
J 0
(-3275 3025);
DISPLAY 0.872340 (-3275 3025);
PAINT GREEN (-3275 3025);
DISPLAY INVISIBLE (-3275 3025);
FORCEPROP 1 LAST HDL_TAP TRUE
J 0
(-2950 2850);
DISPLAY 0.872340 (-2950 2850);
DISPLAY INVISIBLE (-2950 2850);
FORCEPROP 1 LAST PATH I226
J 0
(-3277 2975);
DISPLAY 0.872340 (-3277 2975);
PAINT GREEN (-3277 2975);
DISPLAY INVISIBLE (-3277 2975);
FORCEADD TAP..1
(-3275 3025);
FORCEPROP 3 LASTPIN (-3325 3025) SIG_NAME M_B_CPU0_SB_DQ<19>
J 0
(-3315 3035);
DISPLAY 0.659574 (-3315 3035);
PAINT MONO (-3315 3035);
DISPLAY INVISIBLE (-3315 3035);
FORCEPROP 1 LASTPIN (-3325 3025) BN 19
J 0
(-3337 3033);
DISPLAY 0.489362 (-3337 3033);
PAINT GREEN (-3337 3033);
FORCEPROP 2 LAST CDS_LIB mstr_standard
J 0
(-3275 3025);
DISPLAY 0.723404 (-3275 3025);
PAINT MONO (-3275 3025);
DISPLAY INVISIBLE (-3275 3025);
FORCEPROP 1 LAST BODY_TYPE PLUMBING
J 0
(-3275 3075);
DISPLAY 0.872340 (-3275 3075);
PAINT GREEN (-3275 3075);
DISPLAY INVISIBLE (-3275 3075);
FORCEPROP 1 LAST HDL_TAP TRUE
J 0
(-2950 2900);
DISPLAY 0.872340 (-2950 2900);
DISPLAY INVISIBLE (-2950 2900);
FORCEPROP 1 LAST PATH I227
J 0
(-3277 3025);
DISPLAY 0.872340 (-3277 3025);
PAINT GREEN (-3277 3025);
DISPLAY INVISIBLE (-3277 3025);
FORCEADD TAP..1
(-3275 2825);
FORCEPROP 3 LASTPIN (-3325 2825) SIG_NAME M_B_CPU0_SB_DQ<23>
J 0
(-3315 2835);
DISPLAY 0.659574 (-3315 2835);
PAINT MONO (-3315 2835);
DISPLAY INVISIBLE (-3315 2835);
FORCEPROP 1 LASTPIN (-3325 2825) BN 23
J 0
(-3337 2833);
DISPLAY 0.489362 (-3337 2833);
PAINT GREEN (-3337 2833);
FORCEPROP 2 LAST CDS_LIB mstr_standard
J 0
(-3275 2825);
DISPLAY 0.723404 (-3275 2825);
PAINT MONO (-3275 2825);
DISPLAY INVISIBLE (-3275 2825);
FORCEPROP 1 LAST BODY_TYPE PLUMBING
J 0
(-3275 2875);
DISPLAY 0.872340 (-3275 2875);
PAINT GREEN (-3275 2875);
DISPLAY INVISIBLE (-3275 2875);
FORCEPROP 1 LAST HDL_TAP TRUE
J 0
(-2950 2700);
DISPLAY 0.872340 (-2950 2700);
DISPLAY INVISIBLE (-2950 2700);
FORCEPROP 1 LAST PATH I228
J 0
(-3277 2825);
DISPLAY 0.872340 (-3277 2825);
PAINT GREEN (-3277 2825);
DISPLAY INVISIBLE (-3277 2825);
FORCEADD TAP..1
(-3275 2925);
FORCEPROP 3 LASTPIN (-3325 2925) SIG_NAME M_B_CPU0_SB_DQ<21>
J 0
(-3315 2935);
DISPLAY 0.659574 (-3315 2935);
PAINT MONO (-3315 2935);
DISPLAY INVISIBLE (-3315 2935);
FORCEPROP 1 LASTPIN (-3325 2925) BN 21
J 0
(-3337 2933);
DISPLAY 0.489362 (-3337 2933);
PAINT GREEN (-3337 2933);
FORCEPROP 2 LAST CDS_LIB mstr_standard
J 0
(-3275 2925);
DISPLAY 0.723404 (-3275 2925);
PAINT MONO (-3275 2925);
DISPLAY INVISIBLE (-3275 2925);
FORCEPROP 1 LAST BODY_TYPE PLUMBING
J 0
(-3275 2975);
DISPLAY 0.872340 (-3275 2975);
PAINT GREEN (-3275 2975);
DISPLAY INVISIBLE (-3275 2975);
FORCEPROP 1 LAST HDL_TAP TRUE
J 0
(-2950 2800);
DISPLAY 0.872340 (-2950 2800);
DISPLAY INVISIBLE (-2950 2800);
FORCEPROP 1 LAST PATH I229
J 0
(-3277 2925);
DISPLAY 0.872340 (-3277 2925);
PAINT GREEN (-3277 2925);
DISPLAY INVISIBLE (-3277 2925);
FORCEADD TAP..1
(-3275 2875);
FORCEPROP 3 LASTPIN (-3325 2875) SIG_NAME M_B_CPU0_SB_DQ<22>
J 0
(-3315 2885);
DISPLAY 0.659574 (-3315 2885);
PAINT MONO (-3315 2885);
DISPLAY INVISIBLE (-3315 2885);
FORCEPROP 1 LASTPIN (-3325 2875) BN 22
J 0
(-3337 2883);
DISPLAY 0.489362 (-3337 2883);
PAINT GREEN (-3337 2883);
FORCEPROP 2 LAST CDS_LIB mstr_standard
J 0
(-3275 2875);
DISPLAY 0.723404 (-3275 2875);
PAINT MONO (-3275 2875);
DISPLAY INVISIBLE (-3275 2875);
FORCEPROP 1 LAST BODY_TYPE PLUMBING
J 0
(-3275 2925);
DISPLAY 0.872340 (-3275 2925);
PAINT GREEN (-3275 2925);
DISPLAY INVISIBLE (-3275 2925);
FORCEPROP 1 LAST HDL_TAP TRUE
J 0
(-2950 2750);
DISPLAY 0.872340 (-2950 2750);
DISPLAY INVISIBLE (-2950 2750);
FORCEPROP 1 LAST PATH I230
J 0
(-3277 2875);
DISPLAY 0.872340 (-3277 2875);
PAINT GREEN (-3277 2875);
DISPLAY INVISIBLE (-3277 2875);
FORCEADD TAP..1
(-3275 2725);
FORCEPROP 3 LASTPIN (-3325 2725) SIG_NAME M_B_CPU0_SB_DQ<24>
J 0
(-3315 2735);
DISPLAY 0.659574 (-3315 2735);
PAINT MONO (-3315 2735);
DISPLAY INVISIBLE (-3315 2735);
FORCEPROP 1 LASTPIN (-3325 2725) BN 24
J 0
(-3337 2733);
DISPLAY 0.489362 (-3337 2733);
PAINT GREEN (-3337 2733);
FORCEPROP 2 LAST CDS_LIB mstr_standard
J 0
(-3275 2725);
DISPLAY 0.723404 (-3275 2725);
PAINT MONO (-3275 2725);
DISPLAY INVISIBLE (-3275 2725);
FORCEPROP 1 LAST BODY_TYPE PLUMBING
J 0
(-3275 2775);
DISPLAY 0.872340 (-3275 2775);
PAINT GREEN (-3275 2775);
DISPLAY INVISIBLE (-3275 2775);
FORCEPROP 1 LAST HDL_TAP TRUE
J 0
(-2950 2600);
DISPLAY 0.872340 (-2950 2600);
DISPLAY INVISIBLE (-2950 2600);
FORCEPROP 1 LAST PATH I231
J 0
(-3277 2725);
DISPLAY 0.872340 (-3277 2725);
PAINT GREEN (-3277 2725);
DISPLAY INVISIBLE (-3277 2725);
FORCEADD TAP..1
(-3275 2625);
FORCEPROP 3 LASTPIN (-3325 2625) SIG_NAME M_B_CPU0_SB_DQ<26>
J 0
(-3315 2635);
DISPLAY 0.659574 (-3315 2635);
PAINT MONO (-3315 2635);
DISPLAY INVISIBLE (-3315 2635);
FORCEPROP 1 LASTPIN (-3325 2625) BN 26
J 0
(-3337 2633);
DISPLAY 0.489362 (-3337 2633);
PAINT GREEN (-3337 2633);
FORCEPROP 2 LAST CDS_LIB mstr_standard
J 0
(-3275 2625);
DISPLAY 0.723404 (-3275 2625);
PAINT MONO (-3275 2625);
DISPLAY INVISIBLE (-3275 2625);
FORCEPROP 1 LAST BODY_TYPE PLUMBING
J 0
(-3275 2675);
DISPLAY 0.872340 (-3275 2675);
PAINT GREEN (-3275 2675);
DISPLAY INVISIBLE (-3275 2675);
FORCEPROP 1 LAST HDL_TAP TRUE
J 0
(-2950 2500);
DISPLAY 0.872340 (-2950 2500);
DISPLAY INVISIBLE (-2950 2500);
FORCEPROP 1 LAST PATH I232
J 0
(-3277 2625);
DISPLAY 0.872340 (-3277 2625);
PAINT GREEN (-3277 2625);
DISPLAY INVISIBLE (-3277 2625);
FORCEADD TAP..1
(-3275 2675);
FORCEPROP 3 LASTPIN (-3325 2675) SIG_NAME M_B_CPU0_SB_DQ<25>
J 0
(-3315 2685);
DISPLAY 0.659574 (-3315 2685);
PAINT MONO (-3315 2685);
DISPLAY INVISIBLE (-3315 2685);
FORCEPROP 1 LASTPIN (-3325 2675) BN 25
J 0
(-3337 2683);
DISPLAY 0.489362 (-3337 2683);
PAINT GREEN (-3337 2683);
FORCEPROP 2 LAST CDS_LIB mstr_standard
J 0
(-3275 2675);
DISPLAY 0.723404 (-3275 2675);
PAINT MONO (-3275 2675);
DISPLAY INVISIBLE (-3275 2675);
FORCEPROP 1 LAST BODY_TYPE PLUMBING
J 0
(-3275 2725);
DISPLAY 0.872340 (-3275 2725);
PAINT GREEN (-3275 2725);
DISPLAY INVISIBLE (-3275 2725);
FORCEPROP 1 LAST HDL_TAP TRUE
J 0
(-2950 2550);
DISPLAY 0.872340 (-2950 2550);
DISPLAY INVISIBLE (-2950 2550);
FORCEPROP 1 LAST PATH I233
J 0
(-3277 2675);
DISPLAY 0.872340 (-3277 2675);
PAINT GREEN (-3277 2675);
DISPLAY INVISIBLE (-3277 2675);
FORCEADD TAP..1
(-3275 2575);
FORCEPROP 3 LASTPIN (-3325 2575) SIG_NAME M_B_CPU0_SB_DQ<27>
J 0
(-3315 2585);
DISPLAY 0.659574 (-3315 2585);
PAINT MONO (-3315 2585);
DISPLAY INVISIBLE (-3315 2585);
FORCEPROP 1 LASTPIN (-3325 2575) BN 27
J 0
(-3337 2583);
DISPLAY 0.489362 (-3337 2583);
PAINT GREEN (-3337 2583);
FORCEPROP 2 LAST CDS_LIB mstr_standard
J 0
(-3275 2575);
DISPLAY 0.723404 (-3275 2575);
PAINT MONO (-3275 2575);
DISPLAY INVISIBLE (-3275 2575);
FORCEPROP 1 LAST BODY_TYPE PLUMBING
J 0
(-3275 2625);
DISPLAY 0.872340 (-3275 2625);
PAINT GREEN (-3275 2625);
DISPLAY INVISIBLE (-3275 2625);
FORCEPROP 1 LAST HDL_TAP TRUE
J 0
(-2950 2450);
DISPLAY 0.872340 (-2950 2450);
DISPLAY INVISIBLE (-2950 2450);
FORCEPROP 1 LAST PATH I234
J 0
(-3277 2575);
DISPLAY 0.872340 (-3277 2575);
PAINT GREEN (-3277 2575);
DISPLAY INVISIBLE (-3277 2575);
FORCEADD TAP..1
(-3275 2525);
FORCEPROP 3 LASTPIN (-3325 2525) SIG_NAME M_B_CPU0_SB_DQ<28>
J 0
(-3315 2535);
DISPLAY 0.659574 (-3315 2535);
PAINT MONO (-3315 2535);
DISPLAY INVISIBLE (-3315 2535);
FORCEPROP 1 LASTPIN (-3325 2525) BN 28
J 0
(-3337 2533);
DISPLAY 0.489362 (-3337 2533);
PAINT GREEN (-3337 2533);
FORCEPROP 2 LAST CDS_LIB mstr_standard
J 0
(-3275 2525);
DISPLAY 0.723404 (-3275 2525);
PAINT MONO (-3275 2525);
DISPLAY INVISIBLE (-3275 2525);
FORCEPROP 1 LAST BODY_TYPE PLUMBING
J 0
(-3275 2575);
DISPLAY 0.872340 (-3275 2575);
PAINT GREEN (-3275 2575);
DISPLAY INVISIBLE (-3275 2575);
FORCEPROP 1 LAST HDL_TAP TRUE
J 0
(-2950 2400);
DISPLAY 0.872340 (-2950 2400);
DISPLAY INVISIBLE (-2950 2400);
FORCEPROP 1 LAST PATH I235
J 0
(-3277 2525);
DISPLAY 0.872340 (-3277 2525);
PAINT GREEN (-3277 2525);
DISPLAY INVISIBLE (-3277 2525);
FORCEADD TAP..1
(-3275 2475);
FORCEPROP 3 LASTPIN (-3325 2475) SIG_NAME M_B_CPU0_SB_DQ<29>
J 0
(-3315 2485);
DISPLAY 0.659574 (-3315 2485);
PAINT MONO (-3315 2485);
DISPLAY INVISIBLE (-3315 2485);
FORCEPROP 1 LASTPIN (-3325 2475) BN 29
J 0
(-3337 2483);
DISPLAY 0.489362 (-3337 2483);
PAINT GREEN (-3337 2483);
FORCEPROP 2 LAST CDS_LIB mstr_standard
J 0
(-3275 2475);
DISPLAY 0.723404 (-3275 2475);
PAINT MONO (-3275 2475);
DISPLAY INVISIBLE (-3275 2475);
FORCEPROP 1 LAST BODY_TYPE PLUMBING
J 0
(-3275 2525);
DISPLAY 0.872340 (-3275 2525);
PAINT GREEN (-3275 2525);
DISPLAY INVISIBLE (-3275 2525);
FORCEPROP 1 LAST HDL_TAP TRUE
J 0
(-2950 2350);
DISPLAY 0.872340 (-2950 2350);
DISPLAY INVISIBLE (-2950 2350);
FORCEPROP 1 LAST PATH I236
J 0
(-3277 2475);
DISPLAY 0.872340 (-3277 2475);
PAINT GREEN (-3277 2475);
DISPLAY INVISIBLE (-3277 2475);
FORCEADD TAP..1
(-3275 2425);
FORCEPROP 3 LASTPIN (-3325 2425) SIG_NAME M_B_CPU0_SB_DQ<30>
J 0
(-3315 2435);
DISPLAY 0.659574 (-3315 2435);
PAINT MONO (-3315 2435);
DISPLAY INVISIBLE (-3315 2435);
FORCEPROP 1 LASTPIN (-3325 2425) BN 30
J 0
(-3337 2433);
DISPLAY 0.489362 (-3337 2433);
PAINT GREEN (-3337 2433);
FORCEPROP 2 LAST CDS_LIB mstr_standard
J 0
(-3275 2425);
DISPLAY 0.723404 (-3275 2425);
PAINT MONO (-3275 2425);
DISPLAY INVISIBLE (-3275 2425);
FORCEPROP 1 LAST BODY_TYPE PLUMBING
J 0
(-3275 2475);
DISPLAY 0.872340 (-3275 2475);
PAINT GREEN (-3275 2475);
DISPLAY INVISIBLE (-3275 2475);
FORCEPROP 1 LAST HDL_TAP TRUE
J 0
(-2950 2300);
DISPLAY 0.872340 (-2950 2300);
DISPLAY INVISIBLE (-2950 2300);
FORCEPROP 1 LAST PATH I237
J 0
(-3277 2425);
DISPLAY 0.872340 (-3277 2425);
PAINT GREEN (-3277 2425);
DISPLAY INVISIBLE (-3277 2425);
FORCEADD TAP..1
(-3275 2375);
FORCEPROP 3 LASTPIN (-3325 2375) SIG_NAME M_B_CPU0_SB_DQ<31>
J 0
(-3315 2385);
DISPLAY 0.659574 (-3315 2385);
PAINT MONO (-3315 2385);
DISPLAY INVISIBLE (-3315 2385);
FORCEPROP 1 LASTPIN (-3325 2375) BN 31
J 0
(-3337 2383);
DISPLAY 0.489362 (-3337 2383);
PAINT GREEN (-3337 2383);
FORCEPROP 2 LAST CDS_LIB mstr_standard
J 0
(-3275 2375);
DISPLAY 0.723404 (-3275 2375);
PAINT MONO (-3275 2375);
DISPLAY INVISIBLE (-3275 2375);
FORCEPROP 1 LAST BODY_TYPE PLUMBING
J 0
(-3275 2425);
DISPLAY 0.872340 (-3275 2425);
PAINT GREEN (-3275 2425);
DISPLAY INVISIBLE (-3275 2425);
FORCEPROP 1 LAST HDL_TAP TRUE
J 0
(-2950 2250);
DISPLAY 0.872340 (-2950 2250);
DISPLAY INVISIBLE (-2950 2250);
FORCEPROP 1 LAST PATH I238
J 0
(-3277 2375);
DISPLAY 0.872340 (-3277 2375);
PAINT GREEN (-3277 2375);
DISPLAY INVISIBLE (-3277 2375);
FORCEADD TAP..1
(-3275 2275);
FORCEPROP 3 LASTPIN (-3325 2275) SIG_NAME M_B_CPU0_SA_CB<0>
J 0
(-3315 2285);
DISPLAY 0.659574 (-3315 2285);
PAINT MONO (-3315 2285);
DISPLAY INVISIBLE (-3315 2285);
FORCEPROP 1 LASTPIN (-3325 2275) BN 0
J 0
(-3337 2283);
DISPLAY 0.489362 (-3337 2283);
PAINT GREEN (-3337 2283);
FORCEPROP 2 LAST CDS_LIB mstr_standard
J 2
(-3275 2275);
DISPLAY 0.723404 (-3275 2275);
PAINT MONO (-3275 2275);
DISPLAY INVISIBLE (-3275 2275);
FORCEPROP 1 LAST BODY_TYPE PLUMBING
J 0
(-3275 2325);
DISPLAY 0.872340 (-3275 2325);
PAINT GREEN (-3275 2325);
DISPLAY INVISIBLE (-3275 2325);
FORCEPROP 1 LAST HDL_TAP TRUE
J 0
(-2950 2150);
DISPLAY 0.872340 (-2950 2150);
DISPLAY INVISIBLE (-2950 2150);
FORCEPROP 1 LAST PATH I239
J 0
(-3277 2275);
DISPLAY 0.872340 (-3277 2275);
PAINT GREEN (-3277 2275);
DISPLAY INVISIBLE (-3277 2275);
FORCEADD TAP..1
(-3275 2225);
FORCEPROP 3 LASTPIN (-3325 2225) SIG_NAME M_B_CPU0_SA_CB<1>
J 0
(-3315 2235);
DISPLAY 0.659574 (-3315 2235);
PAINT MONO (-3315 2235);
DISPLAY INVISIBLE (-3315 2235);
FORCEPROP 1 LASTPIN (-3325 2225) BN 1
J 0
(-3337 2233);
DISPLAY 0.489362 (-3337 2233);
PAINT GREEN (-3337 2233);
FORCEPROP 2 LAST CDS_LIB mstr_standard
J 2
(-3275 2225);
DISPLAY 0.723404 (-3275 2225);
PAINT MONO (-3275 2225);
DISPLAY INVISIBLE (-3275 2225);
FORCEPROP 1 LAST BODY_TYPE PLUMBING
J 0
(-3275 2275);
DISPLAY 0.872340 (-3275 2275);
PAINT GREEN (-3275 2275);
DISPLAY INVISIBLE (-3275 2275);
FORCEPROP 1 LAST HDL_TAP TRUE
J 0
(-2950 2100);
DISPLAY 0.872340 (-2950 2100);
DISPLAY INVISIBLE (-2950 2100);
FORCEPROP 1 LAST PATH I240
J 0
(-3277 2225);
DISPLAY 0.872340 (-3277 2225);
PAINT GREEN (-3277 2225);
DISPLAY INVISIBLE (-3277 2225);
FORCEADD TAP..1
(-3275 2075);
FORCEPROP 3 LASTPIN (-3325 2075) SIG_NAME M_B_CPU0_SA_CB<4>
J 0
(-3315 2085);
DISPLAY 0.659574 (-3315 2085);
PAINT MONO (-3315 2085);
DISPLAY INVISIBLE (-3315 2085);
FORCEPROP 1 LASTPIN (-3325 2075) BN 4
J 0
(-3337 2083);
DISPLAY 0.489362 (-3337 2083);
PAINT GREEN (-3337 2083);
FORCEPROP 2 LAST CDS_LIB mstr_standard
J 2
(-3275 2075);
DISPLAY 0.723404 (-3275 2075);
PAINT MONO (-3275 2075);
DISPLAY INVISIBLE (-3275 2075);
FORCEPROP 1 LAST BODY_TYPE PLUMBING
J 0
(-3275 2125);
DISPLAY 0.872340 (-3275 2125);
PAINT GREEN (-3275 2125);
DISPLAY INVISIBLE (-3275 2125);
FORCEPROP 1 LAST HDL_TAP TRUE
J 0
(-2950 1950);
DISPLAY 0.872340 (-2950 1950);
DISPLAY INVISIBLE (-2950 1950);
FORCEPROP 1 LAST PATH I241
J 0
(-3277 2075);
DISPLAY 0.872340 (-3277 2075);
PAINT GREEN (-3277 2075);
DISPLAY INVISIBLE (-3277 2075);
FORCEADD TAP..1
(-3275 2175);
FORCEPROP 3 LASTPIN (-3325 2175) SIG_NAME M_B_CPU0_SA_CB<2>
J 0
(-3315 2185);
DISPLAY 0.659574 (-3315 2185);
PAINT MONO (-3315 2185);
DISPLAY INVISIBLE (-3315 2185);
FORCEPROP 1 LASTPIN (-3325 2175) BN 2
J 0
(-3337 2183);
DISPLAY 0.489362 (-3337 2183);
PAINT GREEN (-3337 2183);
FORCEPROP 2 LAST CDS_LIB mstr_standard
J 2
(-3275 2175);
DISPLAY 0.723404 (-3275 2175);
PAINT MONO (-3275 2175);
DISPLAY INVISIBLE (-3275 2175);
FORCEPROP 1 LAST BODY_TYPE PLUMBING
J 0
(-3275 2225);
DISPLAY 0.872340 (-3275 2225);
PAINT GREEN (-3275 2225);
DISPLAY INVISIBLE (-3275 2225);
FORCEPROP 1 LAST HDL_TAP TRUE
J 0
(-2950 2050);
DISPLAY 0.872340 (-2950 2050);
DISPLAY INVISIBLE (-2950 2050);
FORCEPROP 1 LAST PATH I242
J 0
(-3277 2175);
DISPLAY 0.872340 (-3277 2175);
PAINT GREEN (-3277 2175);
DISPLAY INVISIBLE (-3277 2175);
FORCEADD TAP..1
(-3275 2125);
FORCEPROP 3 LASTPIN (-3325 2125) SIG_NAME M_B_CPU0_SA_CB<3>
J 0
(-3315 2135);
DISPLAY 0.659574 (-3315 2135);
PAINT MONO (-3315 2135);
DISPLAY INVISIBLE (-3315 2135);
FORCEPROP 1 LASTPIN (-3325 2125) BN 3
J 0
(-3337 2133);
DISPLAY 0.489362 (-3337 2133);
PAINT GREEN (-3337 2133);
FORCEPROP 2 LAST CDS_LIB mstr_standard
J 2
(-3275 2125);
DISPLAY 0.723404 (-3275 2125);
PAINT MONO (-3275 2125);
DISPLAY INVISIBLE (-3275 2125);
FORCEPROP 1 LAST BODY_TYPE PLUMBING
J 0
(-3275 2175);
DISPLAY 0.872340 (-3275 2175);
PAINT GREEN (-3275 2175);
DISPLAY INVISIBLE (-3275 2175);
FORCEPROP 1 LAST HDL_TAP TRUE
J 0
(-2950 2000);
DISPLAY 0.872340 (-2950 2000);
DISPLAY INVISIBLE (-2950 2000);
FORCEPROP 1 LAST PATH I243
J 0
(-3277 2125);
DISPLAY 0.872340 (-3277 2125);
PAINT GREEN (-3277 2125);
DISPLAY INVISIBLE (-3277 2125);
FORCEADD OFFPAGE..6
R 2
(-2675 1875);
FORCEPROP 2 LAST $XR0 86 
J 0
(-2461 1875);
DISPLAY 0.638298 (-2461 1875);
PAINT MONO (-2461 1875);
FORCEPROP 2 LAST PATH I244
J 0
(-2450 1925);
DISPLAY 1.021277 (-2450 1925);
DISPLAY INVISIBLE (-2450 1925);
FORCEPROP 1 LAST COMMENT_BODY TRUE
J 2
(-2775 1800);
DISPLAY 0.872340 (-2775 1800);
PAINT GREEN (-2775 1800);
DISPLAY INVISIBLE (-2775 1800);
FORCEPROP 1 LAST OFFPAGE TRUE
J 2
(-3000 1750);
DISPLAY 0.872340 (-3000 1750);
PAINT GREEN (-3000 1750);
DISPLAY INVISIBLE (-3000 1750);
FORCEPROP 2 LAST CDS_LIB mstr_standard
J 2
(-2675 1875);
DISPLAY 0.723404 (-2675 1875);
PAINT MONO (-2675 1875);
DISPLAY INVISIBLE (-2675 1875);
FORCEADD TAP..1
(-3275 1925);
FORCEPROP 3 LASTPIN (-3325 1925) SIG_NAME M_B_CPU0_SA_CB<7>
J 0
(-3315 1935);
DISPLAY 0.659574 (-3315 1935);
PAINT MONO (-3315 1935);
DISPLAY INVISIBLE (-3315 1935);
FORCEPROP 1 LASTPIN (-3325 1925) BN 7
J 0
(-3337 1933);
DISPLAY 0.489362 (-3337 1933);
PAINT GREEN (-3337 1933);
FORCEPROP 2 LAST CDS_LIB mstr_standard
J 2
(-3275 1925);
DISPLAY 0.723404 (-3275 1925);
PAINT MONO (-3275 1925);
DISPLAY INVISIBLE (-3275 1925);
FORCEPROP 1 LAST BODY_TYPE PLUMBING
J 0
(-3275 1975);
DISPLAY 0.872340 (-3275 1975);
PAINT GREEN (-3275 1975);
DISPLAY INVISIBLE (-3275 1975);
FORCEPROP 1 LAST HDL_TAP TRUE
J 0
(-2950 1800);
DISPLAY 0.872340 (-2950 1800);
DISPLAY INVISIBLE (-2950 1800);
FORCEPROP 1 LAST PATH I245
J 0
(-3277 1925);
DISPLAY 0.872340 (-3277 1925);
PAINT GREEN (-3277 1925);
DISPLAY INVISIBLE (-3277 1925);
FORCEADD TAP..1
(-3275 2025);
FORCEPROP 3 LASTPIN (-3325 2025) SIG_NAME M_B_CPU0_SA_CB<5>
J 0
(-3315 2035);
DISPLAY 0.659574 (-3315 2035);
PAINT MONO (-3315 2035);
DISPLAY INVISIBLE (-3315 2035);
FORCEPROP 1 LASTPIN (-3325 2025) BN 5
J 0
(-3337 2033);
DISPLAY 0.489362 (-3337 2033);
PAINT GREEN (-3337 2033);
FORCEPROP 2 LAST CDS_LIB mstr_standard
J 2
(-3275 2025);
DISPLAY 0.723404 (-3275 2025);
PAINT MONO (-3275 2025);
DISPLAY INVISIBLE (-3275 2025);
FORCEPROP 1 LAST BODY_TYPE PLUMBING
J 0
(-3275 2075);
DISPLAY 0.872340 (-3275 2075);
PAINT GREEN (-3275 2075);
DISPLAY INVISIBLE (-3275 2075);
FORCEPROP 1 LAST HDL_TAP TRUE
J 0
(-2950 1900);
DISPLAY 0.872340 (-2950 1900);
DISPLAY INVISIBLE (-2950 1900);
FORCEPROP 1 LAST PATH I246
J 0
(-3277 2025);
DISPLAY 0.872340 (-3277 2025);
PAINT GREEN (-3277 2025);
DISPLAY INVISIBLE (-3277 2025);
FORCEADD TAP..1
(-3275 1975);
FORCEPROP 3 LASTPIN (-3325 1975) SIG_NAME M_B_CPU0_SA_CB<6>
J 0
(-3315 1985);
DISPLAY 0.659574 (-3315 1985);
PAINT MONO (-3315 1985);
DISPLAY INVISIBLE (-3315 1985);
FORCEPROP 1 LASTPIN (-3325 1975) BN 6
J 0
(-3337 1983);
DISPLAY 0.489362 (-3337 1983);
PAINT GREEN (-3337 1983);
FORCEPROP 2 LAST CDS_LIB mstr_standard
J 2
(-3275 1975);
DISPLAY 0.723404 (-3275 1975);
PAINT MONO (-3275 1975);
DISPLAY INVISIBLE (-3275 1975);
FORCEPROP 1 LAST BODY_TYPE PLUMBING
J 0
(-3275 2025);
DISPLAY 0.872340 (-3275 2025);
PAINT GREEN (-3275 2025);
DISPLAY INVISIBLE (-3275 2025);
FORCEPROP 1 LAST HDL_TAP TRUE
J 0
(-2950 1850);
DISPLAY 0.872340 (-2950 1850);
DISPLAY INVISIBLE (-2950 1850);
FORCEPROP 1 LAST PATH I247
J 0
(-3277 1975);
DISPLAY 0.872340 (-3277 1975);
PAINT GREEN (-3277 1975);
DISPLAY INVISIBLE (-3277 1975);
FORCEADD TAP..1
(-3275 1825);
FORCEPROP 3 LASTPIN (-3325 1825) SIG_NAME M_B_CPU0_SB_CB<0>
J 0
(-3315 1835);
DISPLAY 0.659574 (-3315 1835);
PAINT MONO (-3315 1835);
DISPLAY INVISIBLE (-3315 1835);
FORCEPROP 1 LASTPIN (-3325 1825) BN 0
J 0
(-3337 1833);
DISPLAY 0.489362 (-3337 1833);
PAINT GREEN (-3337 1833);
FORCEPROP 2 LAST CDS_LIB mstr_standard
J 2
(-3275 1825);
DISPLAY 0.723404 (-3275 1825);
PAINT MONO (-3275 1825);
DISPLAY INVISIBLE (-3275 1825);
FORCEPROP 1 LAST BODY_TYPE PLUMBING
J 0
(-3275 1875);
DISPLAY 0.872340 (-3275 1875);
PAINT GREEN (-3275 1875);
DISPLAY INVISIBLE (-3275 1875);
FORCEPROP 1 LAST HDL_TAP TRUE
J 0
(-2950 1700);
DISPLAY 0.872340 (-2950 1700);
DISPLAY INVISIBLE (-2950 1700);
FORCEPROP 1 LAST PATH I248
J 0
(-3277 1825);
DISPLAY 0.872340 (-3277 1825);
PAINT GREEN (-3277 1825);
DISPLAY INVISIBLE (-3277 1825);
FORCEADD TAP..1
(-3275 1775);
FORCEPROP 3 LASTPIN (-3325 1775) SIG_NAME M_B_CPU0_SB_CB<1>
J 0
(-3315 1785);
DISPLAY 0.659574 (-3315 1785);
PAINT MONO (-3315 1785);
DISPLAY INVISIBLE (-3315 1785);
FORCEPROP 1 LASTPIN (-3325 1775) BN 1
J 0
(-3337 1783);
DISPLAY 0.489362 (-3337 1783);
PAINT GREEN (-3337 1783);
FORCEPROP 2 LAST CDS_LIB mstr_standard
J 2
(-3275 1775);
DISPLAY 0.723404 (-3275 1775);
PAINT MONO (-3275 1775);
DISPLAY INVISIBLE (-3275 1775);
FORCEPROP 1 LAST BODY_TYPE PLUMBING
J 0
(-3275 1825);
DISPLAY 0.872340 (-3275 1825);
PAINT GREEN (-3275 1825);
DISPLAY INVISIBLE (-3275 1825);
FORCEPROP 1 LAST HDL_TAP TRUE
J 0
(-2950 1650);
DISPLAY 0.872340 (-2950 1650);
DISPLAY INVISIBLE (-2950 1650);
FORCEPROP 1 LAST PATH I249
J 0
(-3277 1775);
DISPLAY 0.872340 (-3277 1775);
PAINT GREEN (-3277 1775);
DISPLAY INVISIBLE (-3277 1775);
FORCEADD TAP..1
(-3275 1725);
FORCEPROP 3 LASTPIN (-3325 1725) SIG_NAME M_B_CPU0_SB_CB<2>
J 0
(-3315 1735);
DISPLAY 0.659574 (-3315 1735);
PAINT MONO (-3315 1735);
DISPLAY INVISIBLE (-3315 1735);
FORCEPROP 1 LASTPIN (-3325 1725) BN 2
J 0
(-3337 1733);
DISPLAY 0.489362 (-3337 1733);
PAINT GREEN (-3337 1733);
FORCEPROP 2 LAST CDS_LIB mstr_standard
J 2
(-3275 1725);
DISPLAY 0.723404 (-3275 1725);
PAINT MONO (-3275 1725);
DISPLAY INVISIBLE (-3275 1725);
FORCEPROP 1 LAST BODY_TYPE PLUMBING
J 0
(-3275 1775);
DISPLAY 0.872340 (-3275 1775);
PAINT GREEN (-3275 1775);
DISPLAY INVISIBLE (-3275 1775);
FORCEPROP 1 LAST HDL_TAP TRUE
J 0
(-2950 1600);
DISPLAY 0.872340 (-2950 1600);
DISPLAY INVISIBLE (-2950 1600);
FORCEPROP 1 LAST PATH I250
J 0
(-3277 1725);
DISPLAY 0.872340 (-3277 1725);
PAINT GREEN (-3277 1725);
DISPLAY INVISIBLE (-3277 1725);
FORCEADD TAP..1
(-3275 1675);
FORCEPROP 3 LASTPIN (-3325 1675) SIG_NAME M_B_CPU0_SB_CB<3>
J 0
(-3315 1685);
DISPLAY 0.659574 (-3315 1685);
PAINT MONO (-3315 1685);
DISPLAY INVISIBLE (-3315 1685);
FORCEPROP 1 LASTPIN (-3325 1675) BN 3
J 0
(-3337 1683);
DISPLAY 0.489362 (-3337 1683);
PAINT GREEN (-3337 1683);
FORCEPROP 2 LAST CDS_LIB mstr_standard
J 2
(-3275 1675);
DISPLAY 0.723404 (-3275 1675);
PAINT MONO (-3275 1675);
DISPLAY INVISIBLE (-3275 1675);
FORCEPROP 1 LAST BODY_TYPE PLUMBING
J 0
(-3275 1725);
DISPLAY 0.872340 (-3275 1725);
PAINT GREEN (-3275 1725);
DISPLAY INVISIBLE (-3275 1725);
FORCEPROP 1 LAST HDL_TAP TRUE
J 0
(-2950 1550);
DISPLAY 0.872340 (-2950 1550);
DISPLAY INVISIBLE (-2950 1550);
FORCEPROP 1 LAST PATH I251
J 0
(-3277 1675);
DISPLAY 0.872340 (-3277 1675);
PAINT GREEN (-3277 1675);
DISPLAY INVISIBLE (-3277 1675);
FORCEADD TAP..1
(-3275 1625);
FORCEPROP 3 LASTPIN (-3325 1625) SIG_NAME M_B_CPU0_SB_CB<4>
J 0
(-3315 1635);
DISPLAY 0.659574 (-3315 1635);
PAINT MONO (-3315 1635);
DISPLAY INVISIBLE (-3315 1635);
FORCEPROP 1 LASTPIN (-3325 1625) BN 4
J 0
(-3337 1633);
DISPLAY 0.489362 (-3337 1633);
PAINT GREEN (-3337 1633);
FORCEPROP 2 LAST CDS_LIB mstr_standard
J 2
(-3275 1625);
DISPLAY 0.723404 (-3275 1625);
PAINT MONO (-3275 1625);
DISPLAY INVISIBLE (-3275 1625);
FORCEPROP 1 LAST BODY_TYPE PLUMBING
J 0
(-3275 1675);
DISPLAY 0.872340 (-3275 1675);
PAINT GREEN (-3275 1675);
DISPLAY INVISIBLE (-3275 1675);
FORCEPROP 1 LAST HDL_TAP TRUE
J 0
(-2950 1500);
DISPLAY 0.872340 (-2950 1500);
DISPLAY INVISIBLE (-2950 1500);
FORCEPROP 1 LAST PATH I252
J 0
(-3277 1625);
DISPLAY 0.872340 (-3277 1625);
PAINT GREEN (-3277 1625);
DISPLAY INVISIBLE (-3277 1625);
FORCEADD TAP..1
(-3275 1575);
FORCEPROP 3 LASTPIN (-3325 1575) SIG_NAME M_B_CPU0_SB_CB<5>
J 0
(-3315 1585);
DISPLAY 0.659574 (-3315 1585);
PAINT MONO (-3315 1585);
DISPLAY INVISIBLE (-3315 1585);
FORCEPROP 1 LASTPIN (-3325 1575) BN 5
J 0
(-3337 1583);
DISPLAY 0.489362 (-3337 1583);
PAINT GREEN (-3337 1583);
FORCEPROP 2 LAST CDS_LIB mstr_standard
J 2
(-3275 1575);
DISPLAY 0.723404 (-3275 1575);
PAINT MONO (-3275 1575);
DISPLAY INVISIBLE (-3275 1575);
FORCEPROP 1 LAST BODY_TYPE PLUMBING
J 0
(-3275 1625);
DISPLAY 0.872340 (-3275 1625);
PAINT GREEN (-3275 1625);
DISPLAY INVISIBLE (-3275 1625);
FORCEPROP 1 LAST HDL_TAP TRUE
J 0
(-2950 1450);
DISPLAY 0.872340 (-2950 1450);
DISPLAY INVISIBLE (-2950 1450);
FORCEPROP 1 LAST PATH I253
J 0
(-3277 1575);
DISPLAY 0.872340 (-3277 1575);
PAINT GREEN (-3277 1575);
DISPLAY INVISIBLE (-3277 1575);
FORCEADD TAP..1
(-3275 1475);
FORCEPROP 3 LASTPIN (-3325 1475) SIG_NAME M_B_CPU0_SB_CB<7>
J 0
(-3315 1485);
DISPLAY 0.659574 (-3315 1485);
PAINT MONO (-3315 1485);
DISPLAY INVISIBLE (-3315 1485);
FORCEPROP 1 LASTPIN (-3325 1475) BN 7
J 0
(-3337 1483);
DISPLAY 0.489362 (-3337 1483);
PAINT GREEN (-3337 1483);
FORCEPROP 2 LAST CDS_LIB mstr_standard
J 2
(-3275 1475);
DISPLAY 0.723404 (-3275 1475);
PAINT MONO (-3275 1475);
DISPLAY INVISIBLE (-3275 1475);
FORCEPROP 1 LAST BODY_TYPE PLUMBING
J 0
(-3275 1525);
DISPLAY 0.872340 (-3275 1525);
PAINT GREEN (-3275 1525);
DISPLAY INVISIBLE (-3275 1525);
FORCEPROP 1 LAST HDL_TAP TRUE
J 0
(-2950 1350);
DISPLAY 0.872340 (-2950 1350);
DISPLAY INVISIBLE (-2950 1350);
FORCEPROP 1 LAST PATH I254
J 0
(-3277 1475);
DISPLAY 0.872340 (-3277 1475);
PAINT GREEN (-3277 1475);
DISPLAY INVISIBLE (-3277 1475);
FORCEADD TAP..1
(-3275 1525);
FORCEPROP 3 LASTPIN (-3325 1525) SIG_NAME M_B_CPU0_SB_CB<6>
J 0
(-3315 1535);
DISPLAY 0.659574 (-3315 1535);
PAINT MONO (-3315 1535);
DISPLAY INVISIBLE (-3315 1535);
FORCEPROP 1 LASTPIN (-3325 1525) BN 6
J 0
(-3337 1533);
DISPLAY 0.489362 (-3337 1533);
PAINT GREEN (-3337 1533);
FORCEPROP 2 LAST CDS_LIB mstr_standard
J 2
(-3275 1525);
DISPLAY 0.723404 (-3275 1525);
PAINT MONO (-3275 1525);
DISPLAY INVISIBLE (-3275 1525);
FORCEPROP 1 LAST BODY_TYPE PLUMBING
J 0
(-3275 1575);
DISPLAY 0.872340 (-3275 1575);
PAINT GREEN (-3275 1575);
DISPLAY INVISIBLE (-3275 1575);
FORCEPROP 1 LAST HDL_TAP TRUE
J 0
(-2950 1400);
DISPLAY 0.872340 (-2950 1400);
DISPLAY INVISIBLE (-2950 1400);
FORCEPROP 1 LAST PATH I255
J 0
(-3277 1525);
DISPLAY 0.872340 (-3277 1525);
PAINT GREEN (-3277 1525);
DISPLAY INVISIBLE (-3277 1525);
FORCEADD TAP..1
R 2
(-5700 5875);
FORCEPROP 3 LASTPIN (-5650 5875) SIG_NAME M_B_CPU0_SA_DQS_DP<0>
J 0
(-5640 5885);
DISPLAY 0.659574 (-5640 5885);
PAINT MONO (-5640 5885);
DISPLAY INVISIBLE (-5640 5885);
FORCEPROP 1 LASTPIN (-5650 5875) BN 0
J 2
(-5638 5883);
DISPLAY 0.489362 (-5638 5883);
PAINT GREEN (-5638 5883);
FORCEPROP 2 LAST CDS_LIB mstr_standard
J 2
(-5700 5875);
DISPLAY 0.723404 (-5700 5875);
PAINT MONO (-5700 5875);
DISPLAY INVISIBLE (-5700 5875);
FORCEPROP 1 LAST BODY_TYPE PLUMBING
J 2
(-5700 5925);
DISPLAY 0.872340 (-5700 5925);
PAINT GREEN (-5700 5925);
DISPLAY INVISIBLE (-5700 5925);
FORCEPROP 1 LAST HDL_TAP TRUE
J 2
(-6025 5750);
DISPLAY 0.872340 (-6025 5750);
DISPLAY INVISIBLE (-6025 5750);
FORCEPROP 1 LAST PATH I256
J 2
(-5698 5875);
DISPLAY 0.872340 (-5698 5875);
PAINT GREEN (-5698 5875);
DISPLAY INVISIBLE (-5698 5875);
FORCEADD TAP..1
R 2
(-5700 5775);
FORCEPROP 3 LASTPIN (-5650 5775) SIG_NAME M_B_CPU0_SA_DQS_DP<1>
J 0
(-5640 5785);
DISPLAY 0.659574 (-5640 5785);
PAINT MONO (-5640 5785);
DISPLAY INVISIBLE (-5640 5785);
FORCEPROP 1 LASTPIN (-5650 5775) BN 1
J 2
(-5638 5783);
DISPLAY 0.489362 (-5638 5783);
PAINT GREEN (-5638 5783);
FORCEPROP 2 LAST CDS_LIB mstr_standard
J 2
(-5700 5775);
DISPLAY 0.723404 (-5700 5775);
PAINT MONO (-5700 5775);
DISPLAY INVISIBLE (-5700 5775);
FORCEPROP 1 LAST BODY_TYPE PLUMBING
J 2
(-5700 5825);
DISPLAY 0.872340 (-5700 5825);
PAINT GREEN (-5700 5825);
DISPLAY INVISIBLE (-5700 5825);
FORCEPROP 1 LAST HDL_TAP TRUE
J 2
(-6025 5650);
DISPLAY 0.872340 (-6025 5650);
DISPLAY INVISIBLE (-6025 5650);
FORCEPROP 1 LAST PATH I257
J 2
(-5698 5775);
DISPLAY 0.872340 (-5698 5775);
PAINT GREEN (-5698 5775);
DISPLAY INVISIBLE (-5698 5775);
FORCEADD TAP..1
R 2
(-5700 5675);
FORCEPROP 3 LASTPIN (-5650 5675) SIG_NAME M_B_CPU0_SA_DQS_DP<2>
J 0
(-5640 5685);
DISPLAY 0.659574 (-5640 5685);
PAINT MONO (-5640 5685);
DISPLAY INVISIBLE (-5640 5685);
FORCEPROP 1 LASTPIN (-5650 5675) BN 2
J 2
(-5638 5683);
DISPLAY 0.489362 (-5638 5683);
PAINT GREEN (-5638 5683);
FORCEPROP 2 LAST CDS_LIB mstr_standard
J 2
(-5700 5675);
DISPLAY 0.723404 (-5700 5675);
PAINT MONO (-5700 5675);
DISPLAY INVISIBLE (-5700 5675);
FORCEPROP 1 LAST BODY_TYPE PLUMBING
J 2
(-5700 5725);
DISPLAY 0.872340 (-5700 5725);
PAINT GREEN (-5700 5725);
DISPLAY INVISIBLE (-5700 5725);
FORCEPROP 1 LAST HDL_TAP TRUE
J 2
(-6025 5550);
DISPLAY 0.872340 (-6025 5550);
DISPLAY INVISIBLE (-6025 5550);
FORCEPROP 1 LAST PATH I258
J 2
(-5698 5675);
DISPLAY 0.872340 (-5698 5675);
PAINT GREEN (-5698 5675);
DISPLAY INVISIBLE (-5698 5675);
FORCEADD TAP..1
R 2
(-5900 5725);
FORCEPROP 3 LASTPIN (-5850 5725) SIG_NAME M_B_CPU0_SA_DQS_DN<1>
J 0
(-5840 5735);
DISPLAY 0.659574 (-5840 5735);
PAINT MONO (-5840 5735);
DISPLAY INVISIBLE (-5840 5735);
FORCEPROP 1 LASTPIN (-5850 5725) BN 1
J 2
(-5838 5733);
DISPLAY 0.489362 (-5838 5733);
PAINT GREEN (-5838 5733);
FORCEPROP 2 LAST CDS_LIB mstr_standard
J 2
(-5900 5725);
DISPLAY 0.723404 (-5900 5725);
PAINT MONO (-5900 5725);
DISPLAY INVISIBLE (-5900 5725);
FORCEPROP 1 LAST BODY_TYPE PLUMBING
J 2
(-5900 5775);
DISPLAY 0.872340 (-5900 5775);
PAINT GREEN (-5900 5775);
DISPLAY INVISIBLE (-5900 5775);
FORCEPROP 1 LAST HDL_TAP TRUE
J 2
(-6225 5600);
DISPLAY 0.872340 (-6225 5600);
DISPLAY INVISIBLE (-6225 5600);
FORCEPROP 1 LAST PATH I259
J 2
(-5898 5725);
DISPLAY 0.872340 (-5898 5725);
PAINT GREEN (-5898 5725);
DISPLAY INVISIBLE (-5898 5725);
FORCEADD TAP..1
R 2
(-5900 5825);
FORCEPROP 3 LASTPIN (-5850 5825) SIG_NAME M_B_CPU0_SA_DQS_DN<0>
J 0
(-5840 5835);
DISPLAY 0.659574 (-5840 5835);
PAINT MONO (-5840 5835);
DISPLAY INVISIBLE (-5840 5835);
FORCEPROP 1 LASTPIN (-5850 5825) BN 0
J 2
(-5838 5833);
DISPLAY 0.489362 (-5838 5833);
PAINT GREEN (-5838 5833);
FORCEPROP 2 LAST CDS_LIB mstr_standard
J 2
(-5900 5825);
DISPLAY 0.723404 (-5900 5825);
PAINT MONO (-5900 5825);
DISPLAY INVISIBLE (-5900 5825);
FORCEPROP 1 LAST BODY_TYPE PLUMBING
J 2
(-5900 5875);
DISPLAY 0.872340 (-5900 5875);
PAINT GREEN (-5900 5875);
DISPLAY INVISIBLE (-5900 5875);
FORCEPROP 1 LAST HDL_TAP TRUE
J 2
(-6225 5700);
DISPLAY 0.872340 (-6225 5700);
DISPLAY INVISIBLE (-6225 5700);
FORCEPROP 1 LAST PATH I260
J 2
(-5898 5825);
DISPLAY 0.872340 (-5898 5825);
PAINT GREEN (-5898 5825);
DISPLAY INVISIBLE (-5898 5825);
FORCEADD TAP..1
R 2
(-5700 5575);
FORCEPROP 3 LASTPIN (-5650 5575) SIG_NAME M_B_CPU0_SA_DQS_DP<3>
J 0
(-5640 5585);
DISPLAY 0.659574 (-5640 5585);
PAINT MONO (-5640 5585);
DISPLAY INVISIBLE (-5640 5585);
FORCEPROP 1 LASTPIN (-5650 5575) BN 3
J 2
(-5638 5583);
DISPLAY 0.489362 (-5638 5583);
PAINT GREEN (-5638 5583);
FORCEPROP 2 LAST CDS_LIB mstr_standard
J 2
(-5700 5575);
DISPLAY 0.723404 (-5700 5575);
PAINT MONO (-5700 5575);
DISPLAY INVISIBLE (-5700 5575);
FORCEPROP 1 LAST BODY_TYPE PLUMBING
J 2
(-5700 5625);
DISPLAY 0.872340 (-5700 5625);
PAINT GREEN (-5700 5625);
DISPLAY INVISIBLE (-5700 5625);
FORCEPROP 1 LAST HDL_TAP TRUE
J 2
(-6025 5450);
DISPLAY 0.872340 (-6025 5450);
DISPLAY INVISIBLE (-6025 5450);
FORCEPROP 1 LAST PATH I261
J 2
(-5698 5575);
DISPLAY 0.872340 (-5698 5575);
PAINT GREEN (-5698 5575);
DISPLAY INVISIBLE (-5698 5575);
FORCEADD TAP..1
R 2
(-5700 5375);
FORCEPROP 3 LASTPIN (-5650 5375) SIG_NAME M_B_CPU0_SA_DQS_DP<5>
J 0
(-5640 5385);
DISPLAY 0.659574 (-5640 5385);
PAINT MONO (-5640 5385);
DISPLAY INVISIBLE (-5640 5385);
FORCEPROP 1 LASTPIN (-5650 5375) BN 5
J 2
(-5638 5383);
DISPLAY 0.489362 (-5638 5383);
PAINT GREEN (-5638 5383);
FORCEPROP 2 LAST CDS_LIB mstr_standard
J 2
(-5700 5375);
DISPLAY 0.723404 (-5700 5375);
PAINT MONO (-5700 5375);
DISPLAY INVISIBLE (-5700 5375);
FORCEPROP 1 LAST BODY_TYPE PLUMBING
J 2
(-5700 5425);
DISPLAY 0.872340 (-5700 5425);
PAINT GREEN (-5700 5425);
DISPLAY INVISIBLE (-5700 5425);
FORCEPROP 1 LAST HDL_TAP TRUE
J 2
(-6025 5250);
DISPLAY 0.872340 (-6025 5250);
DISPLAY INVISIBLE (-6025 5250);
FORCEPROP 1 LAST PATH I262
J 2
(-5698 5375);
DISPLAY 0.872340 (-5698 5375);
PAINT GREEN (-5698 5375);
DISPLAY INVISIBLE (-5698 5375);
FORCEADD TAP..1
R 2
(-5700 5475);
FORCEPROP 3 LASTPIN (-5650 5475) SIG_NAME M_B_CPU0_SA_DQS_DP<4>
J 0
(-5640 5485);
DISPLAY 0.659574 (-5640 5485);
PAINT MONO (-5640 5485);
DISPLAY INVISIBLE (-5640 5485);
FORCEPROP 1 LASTPIN (-5650 5475) BN 4
J 2
(-5638 5483);
DISPLAY 0.489362 (-5638 5483);
PAINT GREEN (-5638 5483);
FORCEPROP 2 LAST CDS_LIB mstr_standard
J 2
(-5700 5475);
DISPLAY 0.723404 (-5700 5475);
PAINT MONO (-5700 5475);
DISPLAY INVISIBLE (-5700 5475);
FORCEPROP 1 LAST BODY_TYPE PLUMBING
J 2
(-5700 5525);
DISPLAY 0.872340 (-5700 5525);
PAINT GREEN (-5700 5525);
DISPLAY INVISIBLE (-5700 5525);
FORCEPROP 1 LAST HDL_TAP TRUE
J 2
(-6025 5350);
DISPLAY 0.872340 (-6025 5350);
DISPLAY INVISIBLE (-6025 5350);
FORCEPROP 1 LAST PATH I263
J 2
(-5698 5475);
DISPLAY 0.872340 (-5698 5475);
PAINT GREEN (-5698 5475);
DISPLAY INVISIBLE (-5698 5475);
FORCEADD TAP..1
R 2
(-5900 5425);
FORCEPROP 3 LASTPIN (-5850 5425) SIG_NAME M_B_CPU0_SA_DQS_DN<4>
J 0
(-5840 5435);
DISPLAY 0.659574 (-5840 5435);
PAINT MONO (-5840 5435);
DISPLAY INVISIBLE (-5840 5435);
FORCEPROP 1 LASTPIN (-5850 5425) BN 4
J 2
(-5838 5433);
DISPLAY 0.489362 (-5838 5433);
PAINT GREEN (-5838 5433);
FORCEPROP 2 LAST CDS_LIB mstr_standard
J 2
(-5900 5425);
DISPLAY 0.723404 (-5900 5425);
PAINT MONO (-5900 5425);
DISPLAY INVISIBLE (-5900 5425);
FORCEPROP 1 LAST BODY_TYPE PLUMBING
J 2
(-5900 5475);
DISPLAY 0.872340 (-5900 5475);
PAINT GREEN (-5900 5475);
DISPLAY INVISIBLE (-5900 5475);
FORCEPROP 1 LAST HDL_TAP TRUE
J 2
(-6225 5300);
DISPLAY 0.872340 (-6225 5300);
DISPLAY INVISIBLE (-6225 5300);
FORCEPROP 1 LAST PATH I264
J 2
(-5898 5425);
DISPLAY 0.872340 (-5898 5425);
PAINT GREEN (-5898 5425);
DISPLAY INVISIBLE (-5898 5425);
FORCEADD TAP..1
R 2
(-5900 5625);
FORCEPROP 3 LASTPIN (-5850 5625) SIG_NAME M_B_CPU0_SA_DQS_DN<2>
J 0
(-5840 5635);
DISPLAY 0.659574 (-5840 5635);
PAINT MONO (-5840 5635);
DISPLAY INVISIBLE (-5840 5635);
FORCEPROP 1 LASTPIN (-5850 5625) BN 2
J 2
(-5838 5633);
DISPLAY 0.489362 (-5838 5633);
PAINT GREEN (-5838 5633);
FORCEPROP 2 LAST CDS_LIB mstr_standard
J 2
(-5900 5625);
DISPLAY 0.723404 (-5900 5625);
PAINT MONO (-5900 5625);
DISPLAY INVISIBLE (-5900 5625);
FORCEPROP 1 LAST BODY_TYPE PLUMBING
J 2
(-5900 5675);
DISPLAY 0.872340 (-5900 5675);
PAINT GREEN (-5900 5675);
DISPLAY INVISIBLE (-5900 5675);
FORCEPROP 1 LAST HDL_TAP TRUE
J 2
(-6225 5500);
DISPLAY 0.872340 (-6225 5500);
DISPLAY INVISIBLE (-6225 5500);
FORCEPROP 1 LAST PATH I265
J 2
(-5898 5625);
DISPLAY 0.872340 (-5898 5625);
PAINT GREEN (-5898 5625);
DISPLAY INVISIBLE (-5898 5625);
FORCEADD TAP..1
R 2
(-5900 5525);
FORCEPROP 3 LASTPIN (-5850 5525) SIG_NAME M_B_CPU0_SA_DQS_DN<3>
J 0
(-5840 5535);
DISPLAY 0.659574 (-5840 5535);
PAINT MONO (-5840 5535);
DISPLAY INVISIBLE (-5840 5535);
FORCEPROP 1 LASTPIN (-5850 5525) BN 3
J 2
(-5838 5533);
DISPLAY 0.489362 (-5838 5533);
PAINT GREEN (-5838 5533);
FORCEPROP 2 LAST CDS_LIB mstr_standard
J 2
(-5900 5525);
DISPLAY 0.723404 (-5900 5525);
PAINT MONO (-5900 5525);
DISPLAY INVISIBLE (-5900 5525);
FORCEPROP 1 LAST BODY_TYPE PLUMBING
J 2
(-5900 5575);
DISPLAY 0.872340 (-5900 5575);
PAINT GREEN (-5900 5575);
DISPLAY INVISIBLE (-5900 5575);
FORCEPROP 1 LAST HDL_TAP TRUE
J 2
(-6225 5400);
DISPLAY 0.872340 (-6225 5400);
DISPLAY INVISIBLE (-6225 5400);
FORCEPROP 1 LAST PATH I266
J 2
(-5898 5525);
DISPLAY 0.872340 (-5898 5525);
PAINT GREEN (-5898 5525);
DISPLAY INVISIBLE (-5898 5525);
FORCEADD TAP..1
R 2
(-5700 5175);
FORCEPROP 3 LASTPIN (-5650 5175) SIG_NAME M_B_CPU0_SA_DQS_DP<7>
J 0
(-5640 5185);
DISPLAY 0.659574 (-5640 5185);
PAINT MONO (-5640 5185);
DISPLAY INVISIBLE (-5640 5185);
FORCEPROP 1 LASTPIN (-5650 5175) BN 7
J 2
(-5638 5183);
DISPLAY 0.489362 (-5638 5183);
PAINT GREEN (-5638 5183);
FORCEPROP 2 LAST CDS_LIB mstr_standard
J 2
(-5700 5175);
DISPLAY 0.723404 (-5700 5175);
PAINT MONO (-5700 5175);
DISPLAY INVISIBLE (-5700 5175);
FORCEPROP 1 LAST BODY_TYPE PLUMBING
J 2
(-5700 5225);
DISPLAY 0.872340 (-5700 5225);
PAINT GREEN (-5700 5225);
DISPLAY INVISIBLE (-5700 5225);
FORCEPROP 1 LAST HDL_TAP TRUE
J 2
(-6025 5050);
DISPLAY 0.872340 (-6025 5050);
DISPLAY INVISIBLE (-6025 5050);
FORCEPROP 1 LAST PATH I267
J 2
(-5698 5175);
DISPLAY 0.872340 (-5698 5175);
PAINT GREEN (-5698 5175);
DISPLAY INVISIBLE (-5698 5175);
FORCEADD TAP..1
R 2
(-5700 5275);
FORCEPROP 3 LASTPIN (-5650 5275) SIG_NAME M_B_CPU0_SA_DQS_DP<6>
J 0
(-5640 5285);
DISPLAY 0.659574 (-5640 5285);
PAINT MONO (-5640 5285);
DISPLAY INVISIBLE (-5640 5285);
FORCEPROP 1 LASTPIN (-5650 5275) BN 6
J 2
(-5638 5283);
DISPLAY 0.489362 (-5638 5283);
PAINT GREEN (-5638 5283);
FORCEPROP 2 LAST CDS_LIB mstr_standard
J 2
(-5700 5275);
DISPLAY 0.723404 (-5700 5275);
PAINT MONO (-5700 5275);
DISPLAY INVISIBLE (-5700 5275);
FORCEPROP 1 LAST BODY_TYPE PLUMBING
J 2
(-5700 5325);
DISPLAY 0.872340 (-5700 5325);
PAINT GREEN (-5700 5325);
DISPLAY INVISIBLE (-5700 5325);
FORCEPROP 1 LAST HDL_TAP TRUE
J 2
(-6025 5150);
DISPLAY 0.872340 (-6025 5150);
DISPLAY INVISIBLE (-6025 5150);
FORCEPROP 1 LAST PATH I268
J 2
(-5698 5275);
DISPLAY 0.872340 (-5698 5275);
PAINT GREEN (-5698 5275);
DISPLAY INVISIBLE (-5698 5275);
FORCEADD TAP..1
R 2
(-5900 5325);
FORCEPROP 3 LASTPIN (-5850 5325) SIG_NAME M_B_CPU0_SA_DQS_DN<5>
J 0
(-5840 5335);
DISPLAY 0.659574 (-5840 5335);
PAINT MONO (-5840 5335);
DISPLAY INVISIBLE (-5840 5335);
FORCEPROP 1 LASTPIN (-5850 5325) BN 5
J 2
(-5838 5333);
DISPLAY 0.489362 (-5838 5333);
PAINT GREEN (-5838 5333);
FORCEPROP 2 LAST CDS_LIB mstr_standard
J 2
(-5900 5325);
DISPLAY 0.723404 (-5900 5325);
PAINT MONO (-5900 5325);
DISPLAY INVISIBLE (-5900 5325);
FORCEPROP 1 LAST BODY_TYPE PLUMBING
J 2
(-5900 5375);
DISPLAY 0.872340 (-5900 5375);
PAINT GREEN (-5900 5375);
DISPLAY INVISIBLE (-5900 5375);
FORCEPROP 1 LAST HDL_TAP TRUE
J 2
(-6225 5200);
DISPLAY 0.872340 (-6225 5200);
DISPLAY INVISIBLE (-6225 5200);
FORCEPROP 1 LAST PATH I269
J 2
(-5898 5325);
DISPLAY 0.872340 (-5898 5325);
PAINT GREEN (-5898 5325);
DISPLAY INVISIBLE (-5898 5325);
FORCEADD TAP..1
R 2
(-5900 5225);
FORCEPROP 3 LASTPIN (-5850 5225) SIG_NAME M_B_CPU0_SA_DQS_DN<6>
J 0
(-5840 5235);
DISPLAY 0.659574 (-5840 5235);
PAINT MONO (-5840 5235);
DISPLAY INVISIBLE (-5840 5235);
FORCEPROP 1 LASTPIN (-5850 5225) BN 6
J 2
(-5838 5233);
DISPLAY 0.489362 (-5838 5233);
PAINT GREEN (-5838 5233);
FORCEPROP 2 LAST CDS_LIB mstr_standard
J 2
(-5900 5225);
DISPLAY 0.723404 (-5900 5225);
PAINT MONO (-5900 5225);
DISPLAY INVISIBLE (-5900 5225);
FORCEPROP 1 LAST BODY_TYPE PLUMBING
J 2
(-5900 5275);
DISPLAY 0.872340 (-5900 5275);
PAINT GREEN (-5900 5275);
DISPLAY INVISIBLE (-5900 5275);
FORCEPROP 1 LAST HDL_TAP TRUE
J 2
(-6225 5100);
DISPLAY 0.872340 (-6225 5100);
DISPLAY INVISIBLE (-6225 5100);
FORCEPROP 1 LAST PATH I270
J 2
(-5898 5225);
DISPLAY 0.872340 (-5898 5225);
PAINT GREEN (-5898 5225);
DISPLAY INVISIBLE (-5898 5225);
FORCEADD TAP..1
R 2
(-5900 5125);
FORCEPROP 3 LASTPIN (-5850 5125) SIG_NAME M_B_CPU0_SA_DQS_DN<7>
J 0
(-5840 5135);
DISPLAY 0.659574 (-5840 5135);
PAINT MONO (-5840 5135);
DISPLAY INVISIBLE (-5840 5135);
FORCEPROP 1 LASTPIN (-5850 5125) BN 7
J 2
(-5838 5133);
DISPLAY 0.489362 (-5838 5133);
PAINT GREEN (-5838 5133);
FORCEPROP 2 LAST CDS_LIB mstr_standard
J 2
(-5900 5125);
DISPLAY 0.723404 (-5900 5125);
PAINT MONO (-5900 5125);
DISPLAY INVISIBLE (-5900 5125);
FORCEPROP 1 LAST BODY_TYPE PLUMBING
J 2
(-5900 5175);
DISPLAY 0.872340 (-5900 5175);
PAINT GREEN (-5900 5175);
DISPLAY INVISIBLE (-5900 5175);
FORCEPROP 1 LAST HDL_TAP TRUE
J 2
(-6225 5000);
DISPLAY 0.872340 (-6225 5000);
DISPLAY INVISIBLE (-6225 5000);
FORCEPROP 1 LAST PATH I271
J 2
(-5898 5125);
DISPLAY 0.872340 (-5898 5125);
PAINT GREEN (-5898 5125);
DISPLAY INVISIBLE (-5898 5125);
FORCEADD TAP..1
R 2
(-5700 4975);
FORCEPROP 3 LASTPIN (-5650 4975) SIG_NAME M_B_CPU0_SA_DQS_DP<9>
J 0
(-5640 4985);
DISPLAY 0.659574 (-5640 4985);
PAINT MONO (-5640 4985);
DISPLAY INVISIBLE (-5640 4985);
FORCEPROP 1 LASTPIN (-5650 4975) BN 9
J 2
(-5638 4983);
DISPLAY 0.489362 (-5638 4983);
PAINT GREEN (-5638 4983);
FORCEPROP 2 LAST CDS_LIB mstr_standard
J 2
(-5700 4975);
DISPLAY 0.723404 (-5700 4975);
PAINT MONO (-5700 4975);
DISPLAY INVISIBLE (-5700 4975);
FORCEPROP 1 LAST BODY_TYPE PLUMBING
J 2
(-5700 5025);
DISPLAY 0.872340 (-5700 5025);
PAINT GREEN (-5700 5025);
DISPLAY INVISIBLE (-5700 5025);
FORCEPROP 1 LAST HDL_TAP TRUE
J 2
(-6025 4850);
DISPLAY 0.872340 (-6025 4850);
DISPLAY INVISIBLE (-6025 4850);
FORCEPROP 1 LAST PATH I272
J 2
(-5698 4975);
DISPLAY 0.872340 (-5698 4975);
PAINT GREEN (-5698 4975);
DISPLAY INVISIBLE (-5698 4975);
FORCEADD TAP..1
R 2
(-5700 5075);
FORCEPROP 3 LASTPIN (-5650 5075) SIG_NAME M_B_CPU0_SA_DQS_DP<8>
J 0
(-5640 5085);
DISPLAY 0.659574 (-5640 5085);
PAINT MONO (-5640 5085);
DISPLAY INVISIBLE (-5640 5085);
FORCEPROP 1 LASTPIN (-5650 5075) BN 8
J 2
(-5638 5083);
DISPLAY 0.489362 (-5638 5083);
PAINT GREEN (-5638 5083);
FORCEPROP 2 LAST CDS_LIB mstr_standard
J 2
(-5700 5075);
DISPLAY 0.723404 (-5700 5075);
PAINT MONO (-5700 5075);
DISPLAY INVISIBLE (-5700 5075);
FORCEPROP 1 LAST BODY_TYPE PLUMBING
J 2
(-5700 5125);
DISPLAY 0.872340 (-5700 5125);
PAINT GREEN (-5700 5125);
DISPLAY INVISIBLE (-5700 5125);
FORCEPROP 1 LAST HDL_TAP TRUE
J 2
(-6025 4950);
DISPLAY 0.872340 (-6025 4950);
DISPLAY INVISIBLE (-6025 4950);
FORCEPROP 1 LAST PATH I273
J 2
(-5698 5075);
DISPLAY 0.872340 (-5698 5075);
PAINT GREEN (-5698 5075);
DISPLAY INVISIBLE (-5698 5075);
FORCEADD TAP..1
R 2
(-5900 5025);
FORCEPROP 3 LASTPIN (-5850 5025) SIG_NAME M_B_CPU0_SA_DQS_DN<8>
J 0
(-5840 5035);
DISPLAY 0.659574 (-5840 5035);
PAINT MONO (-5840 5035);
DISPLAY INVISIBLE (-5840 5035);
FORCEPROP 1 LASTPIN (-5850 5025) BN 8
J 2
(-5838 5033);
DISPLAY 0.489362 (-5838 5033);
PAINT GREEN (-5838 5033);
FORCEPROP 2 LAST CDS_LIB mstr_standard
J 2
(-5900 5025);
DISPLAY 0.723404 (-5900 5025);
PAINT MONO (-5900 5025);
DISPLAY INVISIBLE (-5900 5025);
FORCEPROP 1 LAST BODY_TYPE PLUMBING
J 2
(-5900 5075);
DISPLAY 0.872340 (-5900 5075);
PAINT GREEN (-5900 5075);
DISPLAY INVISIBLE (-5900 5075);
FORCEPROP 1 LAST HDL_TAP TRUE
J 2
(-6225 4900);
DISPLAY 0.872340 (-6225 4900);
DISPLAY INVISIBLE (-6225 4900);
FORCEPROP 1 LAST PATH I274
J 2
(-5898 5025);
DISPLAY 0.872340 (-5898 5025);
PAINT GREEN (-5898 5025);
DISPLAY INVISIBLE (-5898 5025);
FORCEADD TAP..1
R 2
(-5900 4925);
FORCEPROP 3 LASTPIN (-5850 4925) SIG_NAME M_B_CPU0_SA_DQS_DN<9>
J 0
(-5840 4935);
DISPLAY 0.659574 (-5840 4935);
PAINT MONO (-5840 4935);
DISPLAY INVISIBLE (-5840 4935);
FORCEPROP 1 LASTPIN (-5850 4925) BN 9
J 2
(-5838 4933);
DISPLAY 0.489362 (-5838 4933);
PAINT GREEN (-5838 4933);
FORCEPROP 2 LAST CDS_LIB mstr_standard
J 2
(-5900 4925);
DISPLAY 0.723404 (-5900 4925);
PAINT MONO (-5900 4925);
DISPLAY INVISIBLE (-5900 4925);
FORCEPROP 1 LAST BODY_TYPE PLUMBING
J 2
(-5900 4975);
DISPLAY 0.872340 (-5900 4975);
PAINT GREEN (-5900 4975);
DISPLAY INVISIBLE (-5900 4975);
FORCEPROP 1 LAST HDL_TAP TRUE
J 2
(-6225 4800);
DISPLAY 0.872340 (-6225 4800);
DISPLAY INVISIBLE (-6225 4800);
FORCEPROP 1 LAST PATH I275
J 2
(-5898 4925);
DISPLAY 0.872340 (-5898 4925);
PAINT GREEN (-5898 4925);
DISPLAY INVISIBLE (-5898 4925);
FORCEADD TAP..1
R 2
(-5700 4625);
FORCEPROP 3 LASTPIN (-5650 4625) SIG_NAME M_B_CPU0_SB_DQS_DP<2>
J 0
(-5640 4635);
DISPLAY 0.659574 (-5640 4635);
PAINT MONO (-5640 4635);
DISPLAY INVISIBLE (-5640 4635);
FORCEPROP 1 LASTPIN (-5650 4625) BN 2
J 2
(-5638 4633);
DISPLAY 0.489362 (-5638 4633);
PAINT GREEN (-5638 4633);
FORCEPROP 2 LAST CDS_LIB mstr_standard
J 2
(-5700 4625);
DISPLAY 0.723404 (-5700 4625);
PAINT MONO (-5700 4625);
DISPLAY INVISIBLE (-5700 4625);
FORCEPROP 1 LAST BODY_TYPE PLUMBING
J 2
(-5700 4675);
DISPLAY 0.872340 (-5700 4675);
PAINT GREEN (-5700 4675);
DISPLAY INVISIBLE (-5700 4675);
FORCEPROP 1 LAST HDL_TAP TRUE
J 2
(-6025 4500);
DISPLAY 0.872340 (-6025 4500);
DISPLAY INVISIBLE (-6025 4500);
FORCEPROP 1 LAST PATH I276
J 2
(-5698 4625);
DISPLAY 0.872340 (-5698 4625);
PAINT GREEN (-5698 4625);
DISPLAY INVISIBLE (-5698 4625);
FORCEADD TAP..1
R 2
(-5700 4825);
FORCEPROP 3 LASTPIN (-5650 4825) SIG_NAME M_B_CPU0_SB_DQS_DP<0>
J 0
(-5640 4835);
DISPLAY 0.659574 (-5640 4835);
PAINT MONO (-5640 4835);
DISPLAY INVISIBLE (-5640 4835);
FORCEPROP 1 LASTPIN (-5650 4825) BN 0
J 2
(-5638 4833);
DISPLAY 0.489362 (-5638 4833);
PAINT GREEN (-5638 4833);
FORCEPROP 2 LAST CDS_LIB mstr_standard
J 2
(-5700 4825);
DISPLAY 0.723404 (-5700 4825);
PAINT MONO (-5700 4825);
DISPLAY INVISIBLE (-5700 4825);
FORCEPROP 1 LAST BODY_TYPE PLUMBING
J 2
(-5700 4875);
DISPLAY 0.872340 (-5700 4875);
PAINT GREEN (-5700 4875);
DISPLAY INVISIBLE (-5700 4875);
FORCEPROP 1 LAST HDL_TAP TRUE
J 2
(-6025 4700);
DISPLAY 0.872340 (-6025 4700);
DISPLAY INVISIBLE (-6025 4700);
FORCEPROP 1 LAST PATH I277
J 2
(-5698 4825);
DISPLAY 0.872340 (-5698 4825);
PAINT GREEN (-5698 4825);
DISPLAY INVISIBLE (-5698 4825);
FORCEADD TAP..1
R 2
(-5700 4725);
FORCEPROP 3 LASTPIN (-5650 4725) SIG_NAME M_B_CPU0_SB_DQS_DP<1>
J 0
(-5640 4735);
DISPLAY 0.659574 (-5640 4735);
PAINT MONO (-5640 4735);
DISPLAY INVISIBLE (-5640 4735);
FORCEPROP 1 LASTPIN (-5650 4725) BN 1
J 2
(-5638 4733);
DISPLAY 0.489362 (-5638 4733);
PAINT GREEN (-5638 4733);
FORCEPROP 2 LAST CDS_LIB mstr_standard
J 2
(-5700 4725);
DISPLAY 0.723404 (-5700 4725);
PAINT MONO (-5700 4725);
DISPLAY INVISIBLE (-5700 4725);
FORCEPROP 1 LAST BODY_TYPE PLUMBING
J 2
(-5700 4775);
DISPLAY 0.872340 (-5700 4775);
PAINT GREEN (-5700 4775);
DISPLAY INVISIBLE (-5700 4775);
FORCEPROP 1 LAST HDL_TAP TRUE
J 2
(-6025 4600);
DISPLAY 0.872340 (-6025 4600);
DISPLAY INVISIBLE (-6025 4600);
FORCEPROP 1 LAST PATH I278
J 2
(-5698 4725);
DISPLAY 0.872340 (-5698 4725);
PAINT GREEN (-5698 4725);
DISPLAY INVISIBLE (-5698 4725);
FORCEADD TAP..1
R 2
(-5900 4675);
FORCEPROP 3 LASTPIN (-5850 4675) SIG_NAME M_B_CPU0_SB_DQS_DN<1>
J 0
(-5840 4685);
DISPLAY 0.659574 (-5840 4685);
PAINT MONO (-5840 4685);
DISPLAY INVISIBLE (-5840 4685);
FORCEPROP 1 LASTPIN (-5850 4675) BN 1
J 2
(-5838 4683);
DISPLAY 0.489362 (-5838 4683);
PAINT GREEN (-5838 4683);
FORCEPROP 2 LAST CDS_LIB mstr_standard
J 2
(-5900 4675);
DISPLAY 0.723404 (-5900 4675);
PAINT MONO (-5900 4675);
DISPLAY INVISIBLE (-5900 4675);
FORCEPROP 1 LAST BODY_TYPE PLUMBING
J 2
(-5900 4725);
DISPLAY 0.872340 (-5900 4725);
PAINT GREEN (-5900 4725);
DISPLAY INVISIBLE (-5900 4725);
FORCEPROP 1 LAST HDL_TAP TRUE
J 2
(-6225 4550);
DISPLAY 0.872340 (-6225 4550);
DISPLAY INVISIBLE (-6225 4550);
FORCEPROP 1 LAST PATH I279
J 2
(-5898 4675);
DISPLAY 0.872340 (-5898 4675);
PAINT GREEN (-5898 4675);
DISPLAY INVISIBLE (-5898 4675);
FORCEADD TAP..1
R 2
(-5900 4775);
FORCEPROP 3 LASTPIN (-5850 4775) SIG_NAME M_B_CPU0_SB_DQS_DN<0>
J 0
(-5840 4785);
DISPLAY 0.659574 (-5840 4785);
PAINT MONO (-5840 4785);
DISPLAY INVISIBLE (-5840 4785);
FORCEPROP 1 LASTPIN (-5850 4775) BN 0
J 2
(-5838 4783);
DISPLAY 0.489362 (-5838 4783);
PAINT GREEN (-5838 4783);
FORCEPROP 2 LAST CDS_LIB mstr_standard
J 2
(-5900 4775);
DISPLAY 0.723404 (-5900 4775);
PAINT MONO (-5900 4775);
DISPLAY INVISIBLE (-5900 4775);
FORCEPROP 1 LAST BODY_TYPE PLUMBING
J 2
(-5900 4825);
DISPLAY 0.872340 (-5900 4825);
PAINT GREEN (-5900 4825);
DISPLAY INVISIBLE (-5900 4825);
FORCEPROP 1 LAST HDL_TAP TRUE
J 2
(-6225 4650);
DISPLAY 0.872340 (-6225 4650);
DISPLAY INVISIBLE (-6225 4650);
FORCEPROP 1 LAST PATH I280
J 2
(-5898 4775);
DISPLAY 0.872340 (-5898 4775);
PAINT GREEN (-5898 4775);
DISPLAY INVISIBLE (-5898 4775);
FORCEADD TAP..1
R 2
(-5700 4525);
FORCEPROP 3 LASTPIN (-5650 4525) SIG_NAME M_B_CPU0_SB_DQS_DP<3>
J 0
(-5640 4535);
DISPLAY 0.659574 (-5640 4535);
PAINT MONO (-5640 4535);
DISPLAY INVISIBLE (-5640 4535);
FORCEPROP 1 LASTPIN (-5650 4525) BN 3
J 2
(-5638 4533);
DISPLAY 0.489362 (-5638 4533);
PAINT GREEN (-5638 4533);
FORCEPROP 2 LAST CDS_LIB mstr_standard
J 2
(-5700 4525);
DISPLAY 0.723404 (-5700 4525);
PAINT MONO (-5700 4525);
DISPLAY INVISIBLE (-5700 4525);
FORCEPROP 1 LAST BODY_TYPE PLUMBING
J 2
(-5700 4575);
DISPLAY 0.872340 (-5700 4575);
PAINT GREEN (-5700 4575);
DISPLAY INVISIBLE (-5700 4575);
FORCEPROP 1 LAST HDL_TAP TRUE
J 2
(-6025 4400);
DISPLAY 0.872340 (-6025 4400);
DISPLAY INVISIBLE (-6025 4400);
FORCEPROP 1 LAST PATH I281
J 2
(-5698 4525);
DISPLAY 0.872340 (-5698 4525);
PAINT GREEN (-5698 4525);
DISPLAY INVISIBLE (-5698 4525);
FORCEADD TAP..1
R 2
(-5700 4425);
FORCEPROP 3 LASTPIN (-5650 4425) SIG_NAME M_B_CPU0_SB_DQS_DP<4>
J 0
(-5640 4435);
DISPLAY 0.659574 (-5640 4435);
PAINT MONO (-5640 4435);
DISPLAY INVISIBLE (-5640 4435);
FORCEPROP 1 LASTPIN (-5650 4425) BN 4
J 2
(-5638 4433);
DISPLAY 0.489362 (-5638 4433);
PAINT GREEN (-5638 4433);
FORCEPROP 2 LAST CDS_LIB mstr_standard
J 2
(-5700 4425);
DISPLAY 0.723404 (-5700 4425);
PAINT MONO (-5700 4425);
DISPLAY INVISIBLE (-5700 4425);
FORCEPROP 1 LAST BODY_TYPE PLUMBING
J 2
(-5700 4475);
DISPLAY 0.872340 (-5700 4475);
PAINT GREEN (-5700 4475);
DISPLAY INVISIBLE (-5700 4475);
FORCEPROP 1 LAST HDL_TAP TRUE
J 2
(-6025 4300);
DISPLAY 0.872340 (-6025 4300);
DISPLAY INVISIBLE (-6025 4300);
FORCEPROP 1 LAST PATH I282
J 2
(-5698 4425);
DISPLAY 0.872340 (-5698 4425);
PAINT GREEN (-5698 4425);
DISPLAY INVISIBLE (-5698 4425);
FORCEADD TAP..1
R 2
(-5900 4575);
FORCEPROP 3 LASTPIN (-5850 4575) SIG_NAME M_B_CPU0_SB_DQS_DN<2>
J 0
(-5840 4585);
DISPLAY 0.659574 (-5840 4585);
PAINT MONO (-5840 4585);
DISPLAY INVISIBLE (-5840 4585);
FORCEPROP 1 LASTPIN (-5850 4575) BN 2
J 2
(-5838 4583);
DISPLAY 0.489362 (-5838 4583);
PAINT GREEN (-5838 4583);
FORCEPROP 2 LAST CDS_LIB mstr_standard
J 2
(-5900 4575);
DISPLAY 0.723404 (-5900 4575);
PAINT MONO (-5900 4575);
DISPLAY INVISIBLE (-5900 4575);
FORCEPROP 1 LAST BODY_TYPE PLUMBING
J 2
(-5900 4625);
DISPLAY 0.872340 (-5900 4625);
PAINT GREEN (-5900 4625);
DISPLAY INVISIBLE (-5900 4625);
FORCEPROP 1 LAST HDL_TAP TRUE
J 2
(-6225 4450);
DISPLAY 0.872340 (-6225 4450);
DISPLAY INVISIBLE (-6225 4450);
FORCEPROP 1 LAST PATH I283
J 2
(-5898 4575);
DISPLAY 0.872340 (-5898 4575);
PAINT GREEN (-5898 4575);
DISPLAY INVISIBLE (-5898 4575);
FORCEADD TAP..1
R 2
(-5900 4475);
FORCEPROP 3 LASTPIN (-5850 4475) SIG_NAME M_B_CPU0_SB_DQS_DN<3>
J 0
(-5840 4485);
DISPLAY 0.659574 (-5840 4485);
PAINT MONO (-5840 4485);
DISPLAY INVISIBLE (-5840 4485);
FORCEPROP 1 LASTPIN (-5850 4475) BN 3
J 2
(-5838 4483);
DISPLAY 0.489362 (-5838 4483);
PAINT GREEN (-5838 4483);
FORCEPROP 2 LAST CDS_LIB mstr_standard
J 2
(-5900 4475);
DISPLAY 0.723404 (-5900 4475);
PAINT MONO (-5900 4475);
DISPLAY INVISIBLE (-5900 4475);
FORCEPROP 1 LAST BODY_TYPE PLUMBING
J 2
(-5900 4525);
DISPLAY 0.872340 (-5900 4525);
PAINT GREEN (-5900 4525);
DISPLAY INVISIBLE (-5900 4525);
FORCEPROP 1 LAST HDL_TAP TRUE
J 2
(-6225 4350);
DISPLAY 0.872340 (-6225 4350);
DISPLAY INVISIBLE (-6225 4350);
FORCEPROP 1 LAST PATH I284
J 2
(-5898 4475);
DISPLAY 0.872340 (-5898 4475);
PAINT GREEN (-5898 4475);
DISPLAY INVISIBLE (-5898 4475);
FORCEADD TAP..1
R 2
(-5900 4375);
FORCEPROP 3 LASTPIN (-5850 4375) SIG_NAME M_B_CPU0_SB_DQS_DN<4>
J 0
(-5840 4385);
DISPLAY 0.659574 (-5840 4385);
PAINT MONO (-5840 4385);
DISPLAY INVISIBLE (-5840 4385);
FORCEPROP 1 LASTPIN (-5850 4375) BN 4
J 2
(-5838 4383);
DISPLAY 0.489362 (-5838 4383);
PAINT GREEN (-5838 4383);
FORCEPROP 2 LAST CDS_LIB mstr_standard
J 2
(-5900 4375);
DISPLAY 0.723404 (-5900 4375);
PAINT MONO (-5900 4375);
DISPLAY INVISIBLE (-5900 4375);
FORCEPROP 1 LAST BODY_TYPE PLUMBING
J 2
(-5900 4425);
DISPLAY 0.872340 (-5900 4425);
PAINT GREEN (-5900 4425);
DISPLAY INVISIBLE (-5900 4425);
FORCEPROP 1 LAST HDL_TAP TRUE
J 2
(-6225 4250);
DISPLAY 0.872340 (-6225 4250);
DISPLAY INVISIBLE (-6225 4250);
FORCEPROP 1 LAST PATH I285
J 2
(-5898 4375);
DISPLAY 0.872340 (-5898 4375);
PAINT GREEN (-5898 4375);
DISPLAY INVISIBLE (-5898 4375);
FORCEADD TAP..1
R 2
(-5700 4225);
FORCEPROP 3 LASTPIN (-5650 4225) SIG_NAME M_B_CPU0_SB_DQS_DP<6>
J 0
(-5640 4235);
DISPLAY 0.659574 (-5640 4235);
PAINT MONO (-5640 4235);
DISPLAY INVISIBLE (-5640 4235);
FORCEPROP 1 LASTPIN (-5650 4225) BN 6
J 2
(-5638 4233);
DISPLAY 0.489362 (-5638 4233);
PAINT GREEN (-5638 4233);
FORCEPROP 2 LAST CDS_LIB mstr_standard
J 2
(-5700 4225);
DISPLAY 0.723404 (-5700 4225);
PAINT MONO (-5700 4225);
DISPLAY INVISIBLE (-5700 4225);
FORCEPROP 1 LAST BODY_TYPE PLUMBING
J 2
(-5700 4275);
DISPLAY 0.872340 (-5700 4275);
PAINT GREEN (-5700 4275);
DISPLAY INVISIBLE (-5700 4275);
FORCEPROP 1 LAST HDL_TAP TRUE
J 2
(-6025 4100);
DISPLAY 0.872340 (-6025 4100);
DISPLAY INVISIBLE (-6025 4100);
FORCEPROP 1 LAST PATH I286
J 2
(-5698 4225);
DISPLAY 0.872340 (-5698 4225);
PAINT GREEN (-5698 4225);
DISPLAY INVISIBLE (-5698 4225);
FORCEADD TAP..1
R 2
(-5700 4125);
FORCEPROP 3 LASTPIN (-5650 4125) SIG_NAME M_B_CPU0_SB_DQS_DP<7>
J 0
(-5640 4135);
DISPLAY 0.659574 (-5640 4135);
PAINT MONO (-5640 4135);
DISPLAY INVISIBLE (-5640 4135);
FORCEPROP 1 LASTPIN (-5650 4125) BN 7
J 2
(-5638 4133);
DISPLAY 0.489362 (-5638 4133);
PAINT GREEN (-5638 4133);
FORCEPROP 2 LAST CDS_LIB mstr_standard
J 2
(-5700 4125);
DISPLAY 0.723404 (-5700 4125);
PAINT MONO (-5700 4125);
DISPLAY INVISIBLE (-5700 4125);
FORCEPROP 1 LAST BODY_TYPE PLUMBING
J 2
(-5700 4175);
DISPLAY 0.872340 (-5700 4175);
PAINT GREEN (-5700 4175);
DISPLAY INVISIBLE (-5700 4175);
FORCEPROP 1 LAST HDL_TAP TRUE
J 2
(-6025 4000);
DISPLAY 0.872340 (-6025 4000);
DISPLAY INVISIBLE (-6025 4000);
FORCEPROP 1 LAST PATH I287
J 2
(-5698 4125);
DISPLAY 0.872340 (-5698 4125);
PAINT GREEN (-5698 4125);
DISPLAY INVISIBLE (-5698 4125);
FORCEADD TAP..1
R 2
(-5700 4325);
FORCEPROP 3 LASTPIN (-5650 4325) SIG_NAME M_B_CPU0_SB_DQS_DP<5>
J 0
(-5640 4335);
DISPLAY 0.659574 (-5640 4335);
PAINT MONO (-5640 4335);
DISPLAY INVISIBLE (-5640 4335);
FORCEPROP 1 LASTPIN (-5650 4325) BN 5
J 2
(-5638 4333);
DISPLAY 0.489362 (-5638 4333);
PAINT GREEN (-5638 4333);
FORCEPROP 2 LAST CDS_LIB mstr_standard
J 2
(-5700 4325);
DISPLAY 0.723404 (-5700 4325);
PAINT MONO (-5700 4325);
DISPLAY INVISIBLE (-5700 4325);
FORCEPROP 1 LAST BODY_TYPE PLUMBING
J 2
(-5700 4375);
DISPLAY 0.872340 (-5700 4375);
PAINT GREEN (-5700 4375);
DISPLAY INVISIBLE (-5700 4375);
FORCEPROP 1 LAST HDL_TAP TRUE
J 2
(-6025 4200);
DISPLAY 0.872340 (-6025 4200);
DISPLAY INVISIBLE (-6025 4200);
FORCEPROP 1 LAST PATH I288
J 2
(-5698 4325);
DISPLAY 0.872340 (-5698 4325);
PAINT GREEN (-5698 4325);
DISPLAY INVISIBLE (-5698 4325);
FORCEADD TAP..1
R 2
(-5900 4175);
FORCEPROP 3 LASTPIN (-5850 4175) SIG_NAME M_B_CPU0_SB_DQS_DN<6>
J 0
(-5840 4185);
DISPLAY 0.659574 (-5840 4185);
PAINT MONO (-5840 4185);
DISPLAY INVISIBLE (-5840 4185);
FORCEPROP 1 LASTPIN (-5850 4175) BN 6
J 2
(-5838 4183);
DISPLAY 0.489362 (-5838 4183);
PAINT GREEN (-5838 4183);
FORCEPROP 2 LAST CDS_LIB mstr_standard
J 2
(-5900 4175);
DISPLAY 0.723404 (-5900 4175);
PAINT MONO (-5900 4175);
DISPLAY INVISIBLE (-5900 4175);
FORCEPROP 1 LAST BODY_TYPE PLUMBING
J 2
(-5900 4225);
DISPLAY 0.872340 (-5900 4225);
PAINT GREEN (-5900 4225);
DISPLAY INVISIBLE (-5900 4225);
FORCEPROP 1 LAST HDL_TAP TRUE
J 2
(-6225 4050);
DISPLAY 0.872340 (-6225 4050);
DISPLAY INVISIBLE (-6225 4050);
FORCEPROP 1 LAST PATH I289
J 2
(-5898 4175);
DISPLAY 0.872340 (-5898 4175);
PAINT GREEN (-5898 4175);
DISPLAY INVISIBLE (-5898 4175);
FORCEADD TAP..1
R 2
(-5900 4275);
FORCEPROP 3 LASTPIN (-5850 4275) SIG_NAME M_B_CPU0_SB_DQS_DN<5>
J 0
(-5840 4285);
DISPLAY 0.659574 (-5840 4285);
PAINT MONO (-5840 4285);
DISPLAY INVISIBLE (-5840 4285);
FORCEPROP 1 LASTPIN (-5850 4275) BN 5
J 2
(-5838 4283);
DISPLAY 0.489362 (-5838 4283);
PAINT GREEN (-5838 4283);
FORCEPROP 2 LAST CDS_LIB mstr_standard
J 2
(-5900 4275);
DISPLAY 0.723404 (-5900 4275);
PAINT MONO (-5900 4275);
DISPLAY INVISIBLE (-5900 4275);
FORCEPROP 1 LAST BODY_TYPE PLUMBING
J 2
(-5900 4325);
DISPLAY 0.872340 (-5900 4325);
PAINT GREEN (-5900 4325);
DISPLAY INVISIBLE (-5900 4325);
FORCEPROP 1 LAST HDL_TAP TRUE
J 2
(-6225 4150);
DISPLAY 0.872340 (-6225 4150);
DISPLAY INVISIBLE (-6225 4150);
FORCEPROP 1 LAST PATH I290
J 2
(-5898 4275);
DISPLAY 0.872340 (-5898 4275);
PAINT GREEN (-5898 4275);
DISPLAY INVISIBLE (-5898 4275);
FORCEADD OFFPAGE..3
R 2
(-6600 5850);
FORCEPROP 2 LAST $XR0 86 
J 0
(-6879 5850);
DISPLAY 0.638298 (-6879 5850);
PAINT MONO (-6879 5850);
FORCEPROP 2 LAST PATH I291
J 0
(-6875 5900);
DISPLAY 1.021277 (-6875 5900);
DISPLAY INVISIBLE (-6875 5900);
FORCEPROP 1 LAST COMMENT_BODY TRUE
J 2
(-6550 5750);
DISPLAY 0.872340 (-6550 5750);
PAINT GREEN (-6550 5750);
DISPLAY INVISIBLE (-6550 5750);
FORCEPROP 1 LAST OFFPAGE TRUE
J 2
(-6925 5725);
DISPLAY 0.872340 (-6925 5725);
PAINT GREEN (-6925 5725);
DISPLAY INVISIBLE (-6925 5725);
FORCEPROP 2 LAST CDS_LIB standard
J 0
(-6600 5850);
DISPLAY INVISIBLE (-6600 5850);
FORCEADD OFFPAGE..3
R 2
(-6600 5900);
FORCEPROP 2 LAST $XR0 86 
J 0
(-6879 5900);
DISPLAY 0.638298 (-6879 5900);
PAINT MONO (-6879 5900);
FORCEPROP 2 LAST PATH I292
J 0
(-6875 5950);
DISPLAY 1.021277 (-6875 5950);
DISPLAY INVISIBLE (-6875 5950);
FORCEPROP 1 LAST COMMENT_BODY TRUE
J 2
(-6550 5800);
DISPLAY 0.872340 (-6550 5800);
PAINT GREEN (-6550 5800);
DISPLAY INVISIBLE (-6550 5800);
FORCEPROP 1 LAST OFFPAGE TRUE
J 2
(-6925 5775);
DISPLAY 0.872340 (-6925 5775);
PAINT GREEN (-6925 5775);
DISPLAY INVISIBLE (-6925 5775);
FORCEPROP 2 LAST CDS_LIB standard
J 0
(-6600 5900);
DISPLAY INVISIBLE (-6600 5900);
FORCEADD OFFPAGE..3
R 2
(-6600 4850);
FORCEPROP 2 LAST $XR0 86 
J 0
(-6879 4850);
DISPLAY 0.638298 (-6879 4850);
PAINT MONO (-6879 4850);
FORCEPROP 2 LAST PATH I293
J 0
(-6875 4900);
DISPLAY 1.021277 (-6875 4900);
DISPLAY INVISIBLE (-6875 4900);
FORCEPROP 1 LAST COMMENT_BODY TRUE
J 2
(-6550 4750);
DISPLAY 0.872340 (-6550 4750);
PAINT GREEN (-6550 4750);
DISPLAY INVISIBLE (-6550 4750);
FORCEPROP 1 LAST OFFPAGE TRUE
J 2
(-6925 4725);
DISPLAY 0.872340 (-6925 4725);
PAINT GREEN (-6925 4725);
DISPLAY INVISIBLE (-6925 4725);
FORCEPROP 2 LAST CDS_LIB standard
J 0
(-6600 4850);
DISPLAY INVISIBLE (-6600 4850);
FORCEADD OFFPAGE..3
R 2
(-6600 4800);
FORCEPROP 2 LAST $XR0 86 
J 0
(-6879 4800);
DISPLAY 0.638298 (-6879 4800);
PAINT MONO (-6879 4800);
FORCEPROP 2 LAST PATH I294
J 0
(-6875 4850);
DISPLAY 1.021277 (-6875 4850);
DISPLAY INVISIBLE (-6875 4850);
FORCEPROP 1 LAST COMMENT_BODY TRUE
J 2
(-6550 4700);
DISPLAY 0.872340 (-6550 4700);
PAINT GREEN (-6550 4700);
DISPLAY INVISIBLE (-6550 4700);
FORCEPROP 1 LAST OFFPAGE TRUE
J 2
(-6925 4675);
DISPLAY 0.872340 (-6925 4675);
PAINT GREEN (-6925 4675);
DISPLAY INVISIBLE (-6925 4675);
FORCEPROP 2 LAST CDS_LIB standard
J 0
(-6600 4800);
DISPLAY INVISIBLE (-6600 4800);
FORCEADD TAP..1
R 2
(-5700 4025);
FORCEPROP 3 LASTPIN (-5650 4025) SIG_NAME M_B_CPU0_SB_DQS_DP<8>
J 0
(-5640 4035);
DISPLAY 0.659574 (-5640 4035);
PAINT MONO (-5640 4035);
DISPLAY INVISIBLE (-5640 4035);
FORCEPROP 1 LASTPIN (-5650 4025) BN 8
J 2
(-5638 4033);
DISPLAY 0.489362 (-5638 4033);
PAINT GREEN (-5638 4033);
FORCEPROP 2 LAST CDS_LIB mstr_standard
J 2
(-5700 4025);
DISPLAY 0.723404 (-5700 4025);
PAINT MONO (-5700 4025);
DISPLAY INVISIBLE (-5700 4025);
FORCEPROP 1 LAST BODY_TYPE PLUMBING
J 2
(-5700 4075);
DISPLAY 0.872340 (-5700 4075);
PAINT GREEN (-5700 4075);
DISPLAY INVISIBLE (-5700 4075);
FORCEPROP 1 LAST HDL_TAP TRUE
J 2
(-6025 3900);
DISPLAY 0.872340 (-6025 3900);
DISPLAY INVISIBLE (-6025 3900);
FORCEPROP 1 LAST PATH I295
J 2
(-5698 4025);
DISPLAY 0.872340 (-5698 4025);
PAINT GREEN (-5698 4025);
DISPLAY INVISIBLE (-5698 4025);
FORCEADD TAP..1
R 2
(-5700 3925);
FORCEPROP 3 LASTPIN (-5650 3925) SIG_NAME M_B_CPU0_SB_DQS_DP<9>
J 0
(-5640 3935);
DISPLAY 0.659574 (-5640 3935);
PAINT MONO (-5640 3935);
DISPLAY INVISIBLE (-5640 3935);
FORCEPROP 1 LASTPIN (-5650 3925) BN 9
J 2
(-5638 3933);
DISPLAY 0.489362 (-5638 3933);
PAINT GREEN (-5638 3933);
FORCEPROP 2 LAST CDS_LIB mstr_standard
J 2
(-5700 3925);
DISPLAY 0.723404 (-5700 3925);
PAINT MONO (-5700 3925);
DISPLAY INVISIBLE (-5700 3925);
FORCEPROP 1 LAST BODY_TYPE PLUMBING
J 2
(-5700 3975);
DISPLAY 0.872340 (-5700 3975);
PAINT GREEN (-5700 3975);
DISPLAY INVISIBLE (-5700 3975);
FORCEPROP 1 LAST HDL_TAP TRUE
J 2
(-6025 3800);
DISPLAY 0.872340 (-6025 3800);
DISPLAY INVISIBLE (-6025 3800);
FORCEPROP 1 LAST PATH I296
J 2
(-5698 3925);
DISPLAY 0.872340 (-5698 3925);
PAINT GREEN (-5698 3925);
DISPLAY INVISIBLE (-5698 3925);
FORCEADD TAP..1
R 2
(-5900 3875);
FORCEPROP 3 LASTPIN (-5850 3875) SIG_NAME M_B_CPU0_SB_DQS_DN<9>
J 0
(-5840 3885);
DISPLAY 0.659574 (-5840 3885);
PAINT MONO (-5840 3885);
DISPLAY INVISIBLE (-5840 3885);
FORCEPROP 1 LASTPIN (-5850 3875) BN 9
J 2
(-5838 3883);
DISPLAY 0.489362 (-5838 3883);
PAINT GREEN (-5838 3883);
FORCEPROP 2 LAST CDS_LIB mstr_standard
J 2
(-5900 3875);
DISPLAY 0.723404 (-5900 3875);
PAINT MONO (-5900 3875);
DISPLAY INVISIBLE (-5900 3875);
FORCEPROP 1 LAST BODY_TYPE PLUMBING
J 2
(-5900 3925);
DISPLAY 0.872340 (-5900 3925);
PAINT GREEN (-5900 3925);
DISPLAY INVISIBLE (-5900 3925);
FORCEPROP 1 LAST HDL_TAP TRUE
J 2
(-6225 3750);
DISPLAY 0.872340 (-6225 3750);
DISPLAY INVISIBLE (-6225 3750);
FORCEPROP 1 LAST PATH I297
J 2
(-5898 3875);
DISPLAY 0.872340 (-5898 3875);
PAINT GREEN (-5898 3875);
DISPLAY INVISIBLE (-5898 3875);
FORCEADD TAP..1
R 2
(-5900 3975);
FORCEPROP 3 LASTPIN (-5850 3975) SIG_NAME M_B_CPU0_SB_DQS_DN<8>
J 0
(-5840 3985);
DISPLAY 0.659574 (-5840 3985);
PAINT MONO (-5840 3985);
DISPLAY INVISIBLE (-5840 3985);
FORCEPROP 1 LASTPIN (-5850 3975) BN 8
J 2
(-5838 3983);
DISPLAY 0.489362 (-5838 3983);
PAINT GREEN (-5838 3983);
FORCEPROP 2 LAST CDS_LIB mstr_standard
J 2
(-5900 3975);
DISPLAY 0.723404 (-5900 3975);
PAINT MONO (-5900 3975);
DISPLAY INVISIBLE (-5900 3975);
FORCEPROP 1 LAST BODY_TYPE PLUMBING
J 2
(-5900 4025);
DISPLAY 0.872340 (-5900 4025);
PAINT GREEN (-5900 4025);
DISPLAY INVISIBLE (-5900 4025);
FORCEPROP 1 LAST HDL_TAP TRUE
J 2
(-6225 3850);
DISPLAY 0.872340 (-6225 3850);
DISPLAY INVISIBLE (-6225 3850);
FORCEPROP 1 LAST PATH I298
J 2
(-5898 3975);
DISPLAY 0.872340 (-5898 3975);
PAINT GREEN (-5898 3975);
DISPLAY INVISIBLE (-5898 3975);
FORCEADD TAP..1
R 2
(-5900 4075);
FORCEPROP 3 LASTPIN (-5850 4075) SIG_NAME M_B_CPU0_SB_DQS_DN<7>
J 0
(-5840 4085);
DISPLAY 0.659574 (-5840 4085);
PAINT MONO (-5840 4085);
DISPLAY INVISIBLE (-5840 4085);
FORCEPROP 1 LASTPIN (-5850 4075) BN 7
J 2
(-5838 4083);
DISPLAY 0.489362 (-5838 4083);
PAINT GREEN (-5838 4083);
FORCEPROP 2 LAST CDS_LIB mstr_standard
J 2
(-5900 4075);
DISPLAY 0.723404 (-5900 4075);
PAINT MONO (-5900 4075);
DISPLAY INVISIBLE (-5900 4075);
FORCEPROP 1 LAST BODY_TYPE PLUMBING
J 2
(-5900 4125);
DISPLAY 0.872340 (-5900 4125);
PAINT GREEN (-5900 4125);
DISPLAY INVISIBLE (-5900 4125);
FORCEPROP 1 LAST HDL_TAP TRUE
J 2
(-6225 3950);
DISPLAY 0.872340 (-6225 3950);
DISPLAY INVISIBLE (-6225 3950);
FORCEPROP 1 LAST PATH I299
J 2
(-5898 4075);
DISPLAY 0.872340 (-5898 4075);
PAINT GREEN (-5898 4075);
DISPLAY INVISIBLE (-5898 4075);
FORCEADD TAP..1
R 2
(-5900 3725);
FORCEPROP 3 LASTPIN (-5850 3725) SIG_NAME M_B_CPU0_SA_CA<0>
J 0
(-5840 3735);
DISPLAY 0.659574 (-5840 3735);
PAINT MONO (-5840 3735);
DISPLAY INVISIBLE (-5840 3735);
FORCEPROP 1 LASTPIN (-5850 3725) BN 0
J 2
(-5838 3733);
DISPLAY 0.489362 (-5838 3733);
PAINT GREEN (-5838 3733);
FORCEPROP 2 LAST CDS_LIB mstr_standard
J 0
(-5900 3725);
DISPLAY 0.723404 (-5900 3725);
PAINT MONO (-5900 3725);
DISPLAY INVISIBLE (-5900 3725);
FORCEPROP 1 LAST BODY_TYPE PLUMBING
J 2
(-5900 3775);
DISPLAY 0.872340 (-5900 3775);
PAINT GREEN (-5900 3775);
DISPLAY INVISIBLE (-5900 3775);
FORCEPROP 1 LAST HDL_TAP TRUE
J 2
(-6225 3600);
DISPLAY 0.872340 (-6225 3600);
DISPLAY INVISIBLE (-6225 3600);
FORCEPROP 1 LAST PATH I300
J 2
(-5898 3725);
DISPLAY 0.872340 (-5898 3725);
PAINT GREEN (-5898 3725);
DISPLAY INVISIBLE (-5898 3725);
FORCEADD TAP..1
R 2
(-5900 3675);
FORCEPROP 3 LASTPIN (-5850 3675) SIG_NAME M_B_CPU0_SA_CA<1>
J 0
(-5840 3685);
DISPLAY 0.659574 (-5840 3685);
PAINT MONO (-5840 3685);
DISPLAY INVISIBLE (-5840 3685);
FORCEPROP 1 LASTPIN (-5850 3675) BN 1
J 2
(-5838 3683);
DISPLAY 0.489362 (-5838 3683);
PAINT GREEN (-5838 3683);
FORCEPROP 2 LAST CDS_LIB mstr_standard
J 0
(-5900 3675);
DISPLAY 0.723404 (-5900 3675);
PAINT MONO (-5900 3675);
DISPLAY INVISIBLE (-5900 3675);
FORCEPROP 1 LAST BODY_TYPE PLUMBING
J 2
(-5900 3725);
DISPLAY 0.872340 (-5900 3725);
PAINT GREEN (-5900 3725);
DISPLAY INVISIBLE (-5900 3725);
FORCEPROP 1 LAST HDL_TAP TRUE
J 2
(-6225 3550);
DISPLAY 0.872340 (-6225 3550);
DISPLAY INVISIBLE (-6225 3550);
FORCEPROP 1 LAST PATH I301
J 2
(-5898 3675);
DISPLAY 0.872340 (-5898 3675);
PAINT GREEN (-5898 3675);
DISPLAY INVISIBLE (-5898 3675);
FORCEADD TAP..1
R 2
(-5900 3625);
FORCEPROP 3 LASTPIN (-5850 3625) SIG_NAME M_B_CPU0_SA_CA<2>
J 0
(-5840 3635);
DISPLAY 0.659574 (-5840 3635);
PAINT MONO (-5840 3635);
DISPLAY INVISIBLE (-5840 3635);
FORCEPROP 1 LASTPIN (-5850 3625) BN 2
J 2
(-5838 3633);
DISPLAY 0.489362 (-5838 3633);
PAINT GREEN (-5838 3633);
FORCEPROP 2 LAST CDS_LIB mstr_standard
J 0
(-5900 3625);
DISPLAY 0.723404 (-5900 3625);
PAINT MONO (-5900 3625);
DISPLAY INVISIBLE (-5900 3625);
FORCEPROP 1 LAST BODY_TYPE PLUMBING
J 2
(-5900 3675);
DISPLAY 0.872340 (-5900 3675);
PAINT GREEN (-5900 3675);
DISPLAY INVISIBLE (-5900 3675);
FORCEPROP 1 LAST HDL_TAP TRUE
J 2
(-6225 3500);
DISPLAY 0.872340 (-6225 3500);
DISPLAY INVISIBLE (-6225 3500);
FORCEPROP 1 LAST PATH I302
J 2
(-5898 3625);
DISPLAY 0.872340 (-5898 3625);
PAINT GREEN (-5898 3625);
DISPLAY INVISIBLE (-5898 3625);
FORCEADD TAP..1
R 2
(-5900 3525);
FORCEPROP 3 LASTPIN (-5850 3525) SIG_NAME M_B_CPU0_SA_CA<4>
J 0
(-5840 3535);
DISPLAY 0.659574 (-5840 3535);
PAINT MONO (-5840 3535);
DISPLAY INVISIBLE (-5840 3535);
FORCEPROP 1 LASTPIN (-5850 3525) BN 4
J 2
(-5838 3533);
DISPLAY 0.489362 (-5838 3533);
PAINT GREEN (-5838 3533);
FORCEPROP 2 LAST CDS_LIB mstr_standard
J 0
(-5900 3525);
DISPLAY 0.723404 (-5900 3525);
PAINT MONO (-5900 3525);
DISPLAY INVISIBLE (-5900 3525);
FORCEPROP 1 LAST BODY_TYPE PLUMBING
J 2
(-5900 3575);
DISPLAY 0.872340 (-5900 3575);
PAINT GREEN (-5900 3575);
DISPLAY INVISIBLE (-5900 3575);
FORCEPROP 1 LAST HDL_TAP TRUE
J 2
(-6225 3400);
DISPLAY 0.872340 (-6225 3400);
DISPLAY INVISIBLE (-6225 3400);
FORCEPROP 1 LAST PATH I303
J 2
(-5898 3525);
DISPLAY 0.872340 (-5898 3525);
PAINT GREEN (-5898 3525);
DISPLAY INVISIBLE (-5898 3525);
FORCEADD TAP..1
R 2
(-5900 3475);
FORCEPROP 3 LASTPIN (-5850 3475) SIG_NAME M_B_CPU0_SA_CA<5>
J 0
(-5840 3485);
DISPLAY 0.659574 (-5840 3485);
PAINT MONO (-5840 3485);
DISPLAY INVISIBLE (-5840 3485);
FORCEPROP 1 LASTPIN (-5850 3475) BN 5
J 2
(-5838 3483);
DISPLAY 0.489362 (-5838 3483);
PAINT GREEN (-5838 3483);
FORCEPROP 2 LAST CDS_LIB mstr_standard
J 0
(-5900 3475);
DISPLAY 0.723404 (-5900 3475);
PAINT MONO (-5900 3475);
DISPLAY INVISIBLE (-5900 3475);
FORCEPROP 1 LAST BODY_TYPE PLUMBING
J 2
(-5900 3525);
DISPLAY 0.872340 (-5900 3525);
PAINT GREEN (-5900 3525);
DISPLAY INVISIBLE (-5900 3525);
FORCEPROP 1 LAST HDL_TAP TRUE
J 2
(-6225 3350);
DISPLAY 0.872340 (-6225 3350);
DISPLAY INVISIBLE (-6225 3350);
FORCEPROP 1 LAST PATH I304
J 2
(-5898 3475);
DISPLAY 0.872340 (-5898 3475);
PAINT GREEN (-5898 3475);
DISPLAY INVISIBLE (-5898 3475);
FORCEADD TAP..1
R 2
(-5900 3575);
FORCEPROP 3 LASTPIN (-5850 3575) SIG_NAME M_B_CPU0_SA_CA<3>
J 0
(-5840 3585);
DISPLAY 0.659574 (-5840 3585);
PAINT MONO (-5840 3585);
DISPLAY INVISIBLE (-5840 3585);
FORCEPROP 1 LASTPIN (-5850 3575) BN 3
J 2
(-5838 3583);
DISPLAY 0.489362 (-5838 3583);
PAINT GREEN (-5838 3583);
FORCEPROP 2 LAST CDS_LIB mstr_standard
J 0
(-5900 3575);
DISPLAY 0.723404 (-5900 3575);
PAINT MONO (-5900 3575);
DISPLAY INVISIBLE (-5900 3575);
FORCEPROP 1 LAST BODY_TYPE PLUMBING
J 2
(-5900 3625);
DISPLAY 0.872340 (-5900 3625);
PAINT GREEN (-5900 3625);
DISPLAY INVISIBLE (-5900 3625);
FORCEPROP 1 LAST HDL_TAP TRUE
J 2
(-6225 3450);
DISPLAY 0.872340 (-6225 3450);
DISPLAY INVISIBLE (-6225 3450);
FORCEPROP 1 LAST PATH I305
J 2
(-5898 3575);
DISPLAY 0.872340 (-5898 3575);
PAINT GREEN (-5898 3575);
DISPLAY INVISIBLE (-5898 3575);
FORCEADD TAP..1
R 2
(-5900 3425);
FORCEPROP 3 LASTPIN (-5850 3425) SIG_NAME M_B_CPU0_SA_CA<6>
J 0
(-5840 3435);
DISPLAY 0.659574 (-5840 3435);
PAINT MONO (-5840 3435);
DISPLAY INVISIBLE (-5840 3435);
FORCEPROP 1 LASTPIN (-5850 3425) BN 6
J 2
(-5838 3433);
DISPLAY 0.489362 (-5838 3433);
PAINT GREEN (-5838 3433);
FORCEPROP 2 LAST CDS_LIB mstr_standard
J 0
(-5900 3425);
DISPLAY 0.723404 (-5900 3425);
PAINT MONO (-5900 3425);
DISPLAY INVISIBLE (-5900 3425);
FORCEPROP 1 LAST BODY_TYPE PLUMBING
J 2
(-5900 3475);
DISPLAY 0.872340 (-5900 3475);
PAINT GREEN (-5900 3475);
DISPLAY INVISIBLE (-5900 3475);
FORCEPROP 1 LAST HDL_TAP TRUE
J 2
(-6225 3300);
DISPLAY 0.872340 (-6225 3300);
DISPLAY INVISIBLE (-6225 3300);
FORCEPROP 1 LAST PATH I306
J 2
(-5898 3425);
DISPLAY 0.872340 (-5898 3425);
PAINT GREEN (-5898 3425);
DISPLAY INVISIBLE (-5898 3425);
FORCEADD TAP..1
R 2
(-5900 3325);
FORCEPROP 3 LASTPIN (-5850 3325) SIG_NAME M_B_CPU0_SB_CA<0>
J 0
(-5840 3335);
DISPLAY 0.659574 (-5840 3335);
PAINT MONO (-5840 3335);
DISPLAY INVISIBLE (-5840 3335);
FORCEPROP 1 LASTPIN (-5850 3325) BN 0
J 2
(-5838 3333);
DISPLAY 0.489362 (-5838 3333);
PAINT GREEN (-5838 3333);
FORCEPROP 2 LAST CDS_LIB mstr_standard
J 0
(-5900 3325);
DISPLAY 0.723404 (-5900 3325);
PAINT MONO (-5900 3325);
DISPLAY INVISIBLE (-5900 3325);
FORCEPROP 1 LAST BODY_TYPE PLUMBING
J 2
(-5900 3375);
DISPLAY 0.872340 (-5900 3375);
PAINT GREEN (-5900 3375);
DISPLAY INVISIBLE (-5900 3375);
FORCEPROP 1 LAST HDL_TAP TRUE
J 2
(-6225 3200);
DISPLAY 0.872340 (-6225 3200);
DISPLAY INVISIBLE (-6225 3200);
FORCEPROP 1 LAST PATH I307
J 2
(-5898 3325);
DISPLAY 0.872340 (-5898 3325);
PAINT GREEN (-5898 3325);
DISPLAY INVISIBLE (-5898 3325);
FORCEADD TAP..1
R 2
(-5900 3275);
FORCEPROP 3 LASTPIN (-5850 3275) SIG_NAME M_B_CPU0_SB_CA<1>
J 0
(-5840 3285);
DISPLAY 0.659574 (-5840 3285);
PAINT MONO (-5840 3285);
DISPLAY INVISIBLE (-5840 3285);
FORCEPROP 1 LASTPIN (-5850 3275) BN 1
J 2
(-5838 3283);
DISPLAY 0.489362 (-5838 3283);
PAINT GREEN (-5838 3283);
FORCEPROP 2 LAST CDS_LIB mstr_standard
J 0
(-5900 3275);
DISPLAY 0.723404 (-5900 3275);
PAINT MONO (-5900 3275);
DISPLAY INVISIBLE (-5900 3275);
FORCEPROP 1 LAST BODY_TYPE PLUMBING
J 2
(-5900 3325);
DISPLAY 0.872340 (-5900 3325);
PAINT GREEN (-5900 3325);
DISPLAY INVISIBLE (-5900 3325);
FORCEPROP 1 LAST HDL_TAP TRUE
J 2
(-6225 3150);
DISPLAY 0.872340 (-6225 3150);
DISPLAY INVISIBLE (-6225 3150);
FORCEPROP 1 LAST PATH I308
J 2
(-5898 3275);
DISPLAY 0.872340 (-5898 3275);
PAINT GREEN (-5898 3275);
DISPLAY INVISIBLE (-5898 3275);
FORCEADD TAP..1
R 2
(-5900 3225);
FORCEPROP 3 LASTPIN (-5850 3225) SIG_NAME M_B_CPU0_SB_CA<2>
J 0
(-5840 3235);
DISPLAY 0.659574 (-5840 3235);
PAINT MONO (-5840 3235);
DISPLAY INVISIBLE (-5840 3235);
FORCEPROP 1 LASTPIN (-5850 3225) BN 2
J 2
(-5838 3233);
DISPLAY 0.489362 (-5838 3233);
PAINT GREEN (-5838 3233);
FORCEPROP 2 LAST CDS_LIB mstr_standard
J 0
(-5900 3225);
DISPLAY 0.723404 (-5900 3225);
PAINT MONO (-5900 3225);
DISPLAY INVISIBLE (-5900 3225);
FORCEPROP 1 LAST BODY_TYPE PLUMBING
J 2
(-5900 3275);
DISPLAY 0.872340 (-5900 3275);
PAINT GREEN (-5900 3275);
DISPLAY INVISIBLE (-5900 3275);
FORCEPROP 1 LAST HDL_TAP TRUE
J 2
(-6225 3100);
DISPLAY 0.872340 (-6225 3100);
DISPLAY INVISIBLE (-6225 3100);
FORCEPROP 1 LAST PATH I309
J 2
(-5898 3225);
DISPLAY 0.872340 (-5898 3225);
PAINT GREEN (-5898 3225);
DISPLAY INVISIBLE (-5898 3225);
FORCEADD TAP..1
R 2
(-5900 3175);
FORCEPROP 3 LASTPIN (-5850 3175) SIG_NAME M_B_CPU0_SB_CA<3>
J 0
(-5840 3185);
DISPLAY 0.659574 (-5840 3185);
PAINT MONO (-5840 3185);
DISPLAY INVISIBLE (-5840 3185);
FORCEPROP 1 LASTPIN (-5850 3175) BN 3
J 2
(-5838 3183);
DISPLAY 0.489362 (-5838 3183);
PAINT GREEN (-5838 3183);
FORCEPROP 2 LAST CDS_LIB mstr_standard
J 0
(-5900 3175);
DISPLAY 0.723404 (-5900 3175);
PAINT MONO (-5900 3175);
DISPLAY INVISIBLE (-5900 3175);
FORCEPROP 1 LAST BODY_TYPE PLUMBING
J 2
(-5900 3225);
DISPLAY 0.872340 (-5900 3225);
PAINT GREEN (-5900 3225);
DISPLAY INVISIBLE (-5900 3225);
FORCEPROP 1 LAST HDL_TAP TRUE
J 2
(-6225 3050);
DISPLAY 0.872340 (-6225 3050);
DISPLAY INVISIBLE (-6225 3050);
FORCEPROP 1 LAST PATH I310
J 2
(-5898 3175);
DISPLAY 0.872340 (-5898 3175);
PAINT GREEN (-5898 3175);
DISPLAY INVISIBLE (-5898 3175);
FORCEADD TAP..1
R 2
(-5900 3125);
FORCEPROP 3 LASTPIN (-5850 3125) SIG_NAME M_B_CPU0_SB_CA<4>
J 0
(-5840 3135);
DISPLAY 0.659574 (-5840 3135);
PAINT MONO (-5840 3135);
DISPLAY INVISIBLE (-5840 3135);
FORCEPROP 1 LASTPIN (-5850 3125) BN 4
J 2
(-5838 3133);
DISPLAY 0.489362 (-5838 3133);
PAINT GREEN (-5838 3133);
FORCEPROP 2 LAST CDS_LIB mstr_standard
J 0
(-5900 3125);
DISPLAY 0.723404 (-5900 3125);
PAINT MONO (-5900 3125);
DISPLAY INVISIBLE (-5900 3125);
FORCEPROP 1 LAST BODY_TYPE PLUMBING
J 2
(-5900 3175);
DISPLAY 0.872340 (-5900 3175);
PAINT GREEN (-5900 3175);
DISPLAY INVISIBLE (-5900 3175);
FORCEPROP 1 LAST HDL_TAP TRUE
J 2
(-6225 3000);
DISPLAY 0.872340 (-6225 3000);
DISPLAY INVISIBLE (-6225 3000);
FORCEPROP 1 LAST PATH I311
J 2
(-5898 3125);
DISPLAY 0.872340 (-5898 3125);
PAINT GREEN (-5898 3125);
DISPLAY INVISIBLE (-5898 3125);
FORCEADD TAP..1
R 2
(-5900 3075);
FORCEPROP 3 LASTPIN (-5850 3075) SIG_NAME M_B_CPU0_SB_CA<5>
J 0
(-5840 3085);
DISPLAY 0.659574 (-5840 3085);
PAINT MONO (-5840 3085);
DISPLAY INVISIBLE (-5840 3085);
FORCEPROP 1 LASTPIN (-5850 3075) BN 5
J 2
(-5838 3083);
DISPLAY 0.489362 (-5838 3083);
PAINT GREEN (-5838 3083);
FORCEPROP 2 LAST CDS_LIB mstr_standard
J 0
(-5900 3075);
DISPLAY 0.723404 (-5900 3075);
PAINT MONO (-5900 3075);
DISPLAY INVISIBLE (-5900 3075);
FORCEPROP 1 LAST BODY_TYPE PLUMBING
J 2
(-5900 3125);
DISPLAY 0.872340 (-5900 3125);
PAINT GREEN (-5900 3125);
DISPLAY INVISIBLE (-5900 3125);
FORCEPROP 1 LAST HDL_TAP TRUE
J 2
(-6225 2950);
DISPLAY 0.872340 (-6225 2950);
DISPLAY INVISIBLE (-6225 2950);
FORCEPROP 1 LAST PATH I312
J 2
(-5898 3075);
DISPLAY 0.872340 (-5898 3075);
PAINT GREEN (-5898 3075);
DISPLAY INVISIBLE (-5898 3075);
FORCEADD TAP..1
R 2
(-5900 3025);
FORCEPROP 3 LASTPIN (-5850 3025) SIG_NAME M_B_CPU0_SB_CA<6>
J 0
(-5840 3035);
DISPLAY 0.659574 (-5840 3035);
PAINT MONO (-5840 3035);
DISPLAY INVISIBLE (-5840 3035);
FORCEPROP 1 LASTPIN (-5850 3025) BN 6
J 2
(-5838 3033);
DISPLAY 0.489362 (-5838 3033);
PAINT GREEN (-5838 3033);
FORCEPROP 2 LAST CDS_LIB mstr_standard
J 0
(-5900 3025);
DISPLAY 0.723404 (-5900 3025);
PAINT MONO (-5900 3025);
DISPLAY INVISIBLE (-5900 3025);
FORCEPROP 1 LAST BODY_TYPE PLUMBING
J 2
(-5900 3075);
DISPLAY 0.872340 (-5900 3075);
PAINT GREEN (-5900 3075);
DISPLAY INVISIBLE (-5900 3075);
FORCEPROP 1 LAST HDL_TAP TRUE
J 2
(-6225 2900);
DISPLAY 0.872340 (-6225 2900);
DISPLAY INVISIBLE (-6225 2900);
FORCEPROP 1 LAST PATH I313
J 2
(-5898 3025);
DISPLAY 0.872340 (-5898 3025);
PAINT GREEN (-5898 3025);
DISPLAY INVISIBLE (-5898 3025);
FORCEADD OFFPAGE..2
R 2
(-6500 3750);
FORCEPROP 2 LAST $XR0 86 
J 0
(-6754 3750);
DISPLAY 0.638298 (-6754 3750);
PAINT MONO (-6754 3750);
FORCEPROP 2 LAST PATH I314
J 0
(-6775 3800);
DISPLAY 1.021277 (-6775 3800);
DISPLAY INVISIBLE (-6775 3800);
FORCEPROP 1 LAST COMMENT_BODY TRUE
J 2
(-6455 3655);
DISPLAY 0.872340 (-6455 3655);
PAINT GREEN (-6455 3655);
DISPLAY INVISIBLE (-6455 3655);
FORCEPROP 1 LAST OFFPAGE TRUE
J 2
(-6825 3625);
DISPLAY 0.872340 (-6825 3625);
PAINT GREEN (-6825 3625);
DISPLAY INVISIBLE (-6825 3625);
FORCEPROP 2 LAST CDS_LIB standard
J 0
(-6500 3750);
DISPLAY INVISIBLE (-6500 3750);
FORCEADD OFFPAGE..2
R 2
(-6500 3350);
FORCEPROP 2 LAST $XR0 86 
J 0
(-6754 3350);
DISPLAY 0.638298 (-6754 3350);
PAINT MONO (-6754 3350);
FORCEPROP 2 LAST PATH I315
J 0
(-6775 3400);
DISPLAY 1.021277 (-6775 3400);
DISPLAY INVISIBLE (-6775 3400);
FORCEPROP 1 LAST COMMENT_BODY TRUE
J 2
(-6455 3255);
DISPLAY 0.872340 (-6455 3255);
PAINT GREEN (-6455 3255);
DISPLAY INVISIBLE (-6455 3255);
FORCEPROP 1 LAST OFFPAGE TRUE
J 2
(-6825 3225);
DISPLAY 0.872340 (-6825 3225);
PAINT GREEN (-6825 3225);
DISPLAY INVISIBLE (-6825 3225);
FORCEPROP 2 LAST CDS_LIB standard
J 0
(-6500 3350);
DISPLAY INVISIBLE (-6500 3350);
FORCEADD OFFPAGE..2
R 2
(-6500 2875);
FORCEPROP 2 LAST $XR0 86 
J 0
(-6754 2875);
DISPLAY 0.638298 (-6754 2875);
PAINT MONO (-6754 2875);
FORCEPROP 2 LAST PATH I316
J 0
(-6775 2925);
DISPLAY 1.021277 (-6775 2925);
DISPLAY INVISIBLE (-6775 2925);
FORCEPROP 1 LAST COMMENT_BODY TRUE
J 2
(-6455 2780);
DISPLAY 0.872340 (-6455 2780);
PAINT GREEN (-6455 2780);
DISPLAY INVISIBLE (-6455 2780);
FORCEPROP 1 LAST OFFPAGE TRUE
J 2
(-6825 2750);
DISPLAY 0.872340 (-6825 2750);
PAINT GREEN (-6825 2750);
DISPLAY INVISIBLE (-6825 2750);
FORCEPROP 2 LAST CDS_LIB standard
J 0
(-6500 2875);
DISPLAY INVISIBLE (-6500 2875);
FORCEADD OFFPAGE..2
R 2
(-6500 2825);
FORCEPROP 2 LAST $XR0 86 
J 0
(-6754 2825);
DISPLAY 0.638298 (-6754 2825);
PAINT MONO (-6754 2825);
FORCEPROP 2 LAST PATH I317
J 0
(-6775 2875);
DISPLAY 1.021277 (-6775 2875);
DISPLAY INVISIBLE (-6775 2875);
FORCEPROP 1 LAST COMMENT_BODY TRUE
J 2
(-6455 2730);
DISPLAY 0.872340 (-6455 2730);
PAINT GREEN (-6455 2730);
DISPLAY INVISIBLE (-6455 2730);
FORCEPROP 1 LAST OFFPAGE TRUE
J 2
(-6825 2700);
DISPLAY 0.872340 (-6825 2700);
PAINT GREEN (-6825 2700);
DISPLAY INVISIBLE (-6825 2700);
FORCEPROP 2 LAST CDS_LIB standard
J 0
(-6500 2825);
DISPLAY INVISIBLE (-6500 2825);
FORCEADD OFFPAGE..2
R 2
(-6500 2725);
FORCEPROP 2 LAST $XR0 86 
J 0
(-6754 2725);
DISPLAY 0.638298 (-6754 2725);
PAINT MONO (-6754 2725);
FORCEPROP 2 LAST PATH I318
J 0
(-6775 2775);
DISPLAY 1.021277 (-6775 2775);
DISPLAY INVISIBLE (-6775 2775);
FORCEPROP 1 LAST COMMENT_BODY TRUE
J 2
(-6455 2630);
DISPLAY 0.872340 (-6455 2630);
PAINT GREEN (-6455 2630);
DISPLAY INVISIBLE (-6455 2630);
FORCEPROP 1 LAST OFFPAGE TRUE
J 2
(-6825 2600);
DISPLAY 0.872340 (-6825 2600);
PAINT GREEN (-6825 2600);
DISPLAY INVISIBLE (-6825 2600);
FORCEPROP 2 LAST CDS_LIB standard
J 0
(-6500 2725);
DISPLAY INVISIBLE (-6500 2725);
FORCEADD OFFPAGE..2
R 2
(-6500 2675);
FORCEPROP 2 LAST $XR0 86 
J 0
(-6754 2675);
DISPLAY 0.638298 (-6754 2675);
PAINT MONO (-6754 2675);
FORCEPROP 2 LAST PATH I319
J 0
(-6775 2725);
DISPLAY 1.021277 (-6775 2725);
DISPLAY INVISIBLE (-6775 2725);
FORCEPROP 1 LAST COMMENT_BODY TRUE
J 2
(-6455 2580);
DISPLAY 0.872340 (-6455 2580);
PAINT GREEN (-6455 2580);
DISPLAY INVISIBLE (-6455 2580);
FORCEPROP 1 LAST OFFPAGE TRUE
J 2
(-6825 2550);
DISPLAY 0.872340 (-6825 2550);
PAINT GREEN (-6825 2550);
DISPLAY INVISIBLE (-6825 2550);
FORCEPROP 2 LAST CDS_LIB standard
J 0
(-6500 2675);
DISPLAY INVISIBLE (-6500 2675);
FORCEADD OFFPAGE..5
(-6500 2475);
FORCEPROP 2 LAST $XR0 86 
J 0
(-6754 2475);
DISPLAY 0.638298 (-6754 2475);
PAINT MONO (-6754 2475);
FORCEPROP 2 LAST PATH I320
J 0
(-6775 2525);
DISPLAY 1.021277 (-6775 2525);
DISPLAY INVISIBLE (-6775 2525);
FORCEPROP 1 LAST COMMENT_BODY TRUE
J 0
(-6400 2400);
DISPLAY 0.872340 (-6400 2400);
PAINT GREEN (-6400 2400);
DISPLAY INVISIBLE (-6400 2400);
FORCEPROP 1 LAST OFFPAGE TRUE
J 0
(-6175 2350);
DISPLAY 0.872340 (-6175 2350);
PAINT GREEN (-6175 2350);
DISPLAY INVISIBLE (-6175 2350);
FORCEPROP 2 LAST CDS_LIB mstr_standard
J 0
(-6500 2475);
DISPLAY INVISIBLE (-6500 2475);
FORCEADD OFFPAGE..2
R 2
(-6500 2375);
FORCEPROP 2 LAST $XR0 86 
J 0
(-6754 2375);
DISPLAY 0.638298 (-6754 2375);
PAINT MONO (-6754 2375);
FORCEPROP 2 LAST PATH I321
J 0
(-6775 2425);
DISPLAY 1.021277 (-6775 2425);
DISPLAY INVISIBLE (-6775 2425);
FORCEPROP 1 LAST COMMENT_BODY TRUE
J 2
(-6455 2280);
DISPLAY 0.872340 (-6455 2280);
PAINT GREEN (-6455 2280);
DISPLAY INVISIBLE (-6455 2280);
FORCEPROP 1 LAST OFFPAGE TRUE
J 2
(-6825 2250);
DISPLAY 0.872340 (-6825 2250);
PAINT GREEN (-6825 2250);
DISPLAY INVISIBLE (-6825 2250);
FORCEPROP 2 LAST CDS_LIB standard
J 0
(-6500 2375);
DISPLAY INVISIBLE (-6500 2375);
FORCEADD OFFPAGE..1
(-6500 2575);
FORCEPROP 2 LAST $XR0 86 
J 0
(-6721 2575);
DISPLAY 0.638298 (-6721 2575);
PAINT MONO (-6721 2575);
FORCEPROP 2 LAST PATH I322
J 0
(-6750 2625);
DISPLAY 1.021277 (-6750 2625);
DISPLAY INVISIBLE (-6750 2625);
FORCEPROP 1 LAST COMMENT_BODY TRUE
J 0
(-6375 2475);
DISPLAY 0.872340 (-6375 2475);
PAINT GREEN (-6375 2475);
DISPLAY INVISIBLE (-6375 2475);
FORCEPROP 1 LAST OFFPAGE TRUE
J 0
(-6175 2450);
DISPLAY 0.872340 (-6175 2450);
PAINT GREEN (-6175 2450);
DISPLAY INVISIBLE (-6175 2450);
FORCEPROP 2 LAST CDS_LIB standard
J 0
(-6500 2575);
DISPLAY INVISIBLE (-6500 2575);
FORCEADD OFFPAGE..2
R 2
(-6500 2325);
FORCEPROP 2 LAST $XR0 86 
J 0
(-6754 2325);
DISPLAY 0.638298 (-6754 2325);
PAINT MONO (-6754 2325);
FORCEPROP 2 LAST PATH I323
J 0
(-6775 2375);
DISPLAY 1.021277 (-6775 2375);
DISPLAY INVISIBLE (-6775 2375);
FORCEPROP 1 LAST COMMENT_BODY TRUE
J 2
(-6455 2230);
DISPLAY 0.872340 (-6455 2230);
PAINT GREEN (-6455 2230);
DISPLAY INVISIBLE (-6455 2230);
FORCEPROP 1 LAST OFFPAGE TRUE
J 2
(-6825 2200);
DISPLAY 0.872340 (-6825 2200);
PAINT GREEN (-6825 2200);
DISPLAY INVISIBLE (-6825 2200);
FORCEPROP 2 LAST CDS_LIB standard
J 0
(-6500 2325);
DISPLAY INVISIBLE (-6500 2325);
FORCEADD OFFPAGE..5
(-6500 2125);
FORCEPROP 2 LAST $XR0 86 
J 0
(-6754 2125);
DISPLAY 0.638298 (-6754 2125);
PAINT MONO (-6754 2125);
FORCEPROP 2 LAST PATH I324
J 0
(-6775 2175);
DISPLAY 1.021277 (-6775 2175);
DISPLAY INVISIBLE (-6775 2175);
FORCEPROP 1 LAST COMMENT_BODY TRUE
J 0
(-6400 2050);
DISPLAY 0.872340 (-6400 2050);
PAINT GREEN (-6400 2050);
DISPLAY INVISIBLE (-6400 2050);
FORCEPROP 1 LAST OFFPAGE TRUE
J 0
(-6175 2000);
DISPLAY 0.872340 (-6175 2000);
PAINT GREEN (-6175 2000);
DISPLAY INVISIBLE (-6175 2000);
FORCEPROP 2 LAST CDS_LIB standard
J 0
(-6500 2125);
DISPLAY INVISIBLE (-6500 2125);
FORCEADD OFFPAGE..1
(-6500 2225);
FORCEPROP 2 LAST $XR0 86 
J 0
(-6721 2225);
DISPLAY 0.638298 (-6721 2225);
PAINT MONO (-6721 2225);
FORCEPROP 2 LAST PATH I325
J 0
(-6750 2275);
DISPLAY 1.021277 (-6750 2275);
DISPLAY INVISIBLE (-6750 2275);
FORCEPROP 1 LAST COMMENT_BODY TRUE
J 0
(-6375 2125);
DISPLAY 0.872340 (-6375 2125);
PAINT GREEN (-6375 2125);
DISPLAY INVISIBLE (-6375 2125);
FORCEPROP 1 LAST OFFPAGE TRUE
J 0
(-6175 2100);
DISPLAY 0.872340 (-6175 2100);
PAINT GREEN (-6175 2100);
DISPLAY INVISIBLE (-6175 2100);
FORCEPROP 2 LAST CDS_LIB standard
J 0
(-6500 2225);
DISPLAY INVISIBLE (-6500 2225);
FORCEADD OFFPAGE..5
(-6500 1925);
FORCEPROP 2 LAST $XR0 86 
J 0
(-6754 1925);
DISPLAY 0.638298 (-6754 1925);
PAINT MONO (-6754 1925);
FORCEPROP 2 LAST PATH I326
J 0
(-6775 1975);
DISPLAY 1.021277 (-6775 1975);
DISPLAY INVISIBLE (-6775 1975);
FORCEPROP 1 LAST COMMENT_BODY TRUE
J 0
(-6400 1850);
DISPLAY 0.872340 (-6400 1850);
PAINT GREEN (-6400 1850);
DISPLAY INVISIBLE (-6400 1850);
FORCEPROP 1 LAST OFFPAGE TRUE
J 0
(-6175 1800);
DISPLAY 0.872340 (-6175 1800);
PAINT GREEN (-6175 1800);
DISPLAY INVISIBLE (-6175 1800);
FORCEPROP 2 LAST CDS_LIB standard
J 0
(-6500 1925);
DISPLAY INVISIBLE (-6500 1925);
FORCEADD Q_RES..1
(-6825 2025);
FORCEPROP 1 LAST LOCATION R376
J 0
(-7100 2025);
DISPLAY 0.489362 (-7100 2025);
PAINT SKYBLUE (-7100 2025);
FORCEPROP 0 LAST $SEC 1
J 0
(-7000 2075);
DISPLAY 0.680851 (-7000 2075);
PAINT MONO (-7000 2075);
DISPLAY INVISIBLE (-7000 2075);
FORCEPROP 0 LAST CDS_SEC 1
J 0
(-7000 2075);
DISPLAY 1.021277 (-7000 2075);
DISPLAY INVISIBLE (-7000 2075);
FORCEPROP 1 LASTPIN (-6925 2025) $PN 1
J 0
(-6913 2037);
DISPLAY 0.489362 (-6913 2037);
PAINT MONO (-6913 2037);
FORCEPROP 1 LASTPIN (-6725 2025) $PN 2
J 0
(-6763 2037);
DISPLAY 0.489362 (-6763 2037);
PAINT MONO (-6763 2037);
FORCEPROP 1 LAST TOLERANCE 1%
J 0
(-6550 2025);
DISPLAY 0.489362 (-6550 2025);
PAINT SKYBLUE (-6550 2025);
FORCEPROP 1 LAST VALUE 15   
J 2
(-6500 2025);
DISPLAY 0.489362 (-6500 2025);
PAINT SKYBLUE (-6500 2025);
FORCEPROP 1 LAST PART_NUMBER CS01502FB11
J 0
(-6700 2000);
DISPLAY 0.489362 (-6700 2000);
PAINT SKYBLUE (-6700 2000);
FORCEPROP 1 LAST PACK_TYPE 0402LF
J 0
(-7075 2000);
DISPLAY 0.489362 (-7075 2000);
PAINT SKYBLUE (-7075 2000);
FORCEPROP 2 LAST CDS_LIB pure_quanta
J 0
(-6825 2025);
DISPLAY INVISIBLE (-6825 2025);
FORCEPROP 1 LAST PATH I327
J 0
(-6875 2175);
DISPLAY 0.978723 (-6875 2175);
PAINT WHITE (-6875 2175);
DISPLAY INVISIBLE (-6875 2175);
FORCEPROP 1 LAST WATTAGE 1/16W
J 2
(-6600 2150);
DISPLAY 0.638298 (-6600 2150);
PAINT SKYBLUE (-6600 2150);
DISPLAY INVISIBLE (-6600 2150);
FORCEPROP 1 LAST MATERIAL CHIP
J 0
(-6950 2150);
DISPLAY 0.638298 (-6950 2150);
PAINT SKYBLUE (-6950 2150);
DISPLAY INVISIBLE (-6950 2150);
FORCEADD OFFPAGE..1
(-7700 2025);
FORCEPROP 2 LAST $XR0 86 
J 0
(-7951 2025);
DISPLAY 0.638298 (-7951 2025);
PAINT MONO (-7951 2025);
FORCEPROP 2 LAST PATH I328
J 0
(-7975 2075);
DISPLAY 1.021277 (-7975 2075);
DISPLAY INVISIBLE (-7975 2075);
FORCEPROP 1 LAST COMMENT_BODY TRUE
J 0
(-7575 1925);
DISPLAY 0.872340 (-7575 1925);
PAINT GREEN (-7575 1925);
DISPLAY INVISIBLE (-7575 1925);
FORCEPROP 1 LAST OFFPAGE TRUE
J 0
(-7375 1900);
DISPLAY 0.872340 (-7375 1900);
PAINT GREEN (-7375 1900);
DISPLAY INVISIBLE (-7375 1900);
FORCEPROP 2 LAST CDS_LIB mstr_standard
J 0
(-7700 2025);
DISPLAY INVISIBLE (-7700 2025);
FORCEADD CAD_NOTE..1
(-7575 2325);
FORCEPROP 0 LAST L1 R1946 PLACE CLOSE TO CPU < 25MM
J 0
(-7725 2200);
DISPLAY 0.617021 (-7725 2200);
PAINT WHITE (-7725 2200);
FORCEPROP 2 LAST CDS_LIB pure_quanta_power
J 0
(-7575 2325);
DISPLAY INVISIBLE (-7575 2325);
FORCEPROP 1 LAST COMMENT_BODY TRUE
J 0
(-7550 2425);
DISPLAY 0.574468 (-7550 2425);
PAINT WHITE (-7550 2425);
DISPLAY INVISIBLE (-7550 2425);
FORCEADD QUANTA_TITLE_BLOCK_C..1
(0 0);
FORCEPROP 0 LAST CDS_CON_LAST_MODIFIED Fri Mar 11 14:52:11 2022
J 0
(-1885 15);
DISPLAY INVISIBLE (-1885 15);
FORCEPROP 1 LAST CUSTOM_TXT_CDS <CON_LAST_MODIFIED>
J 0
(-1885 15);
DISPLAY 0.978723 (-1885 15);
FORCEPROP 2 LAST CUSTOM_TXT_CDS <XR_PAGE_TITLE>
J 0
(-7890 5250);
DISPLAY 0.638298 (-7890 5250);
PAINT PINK (-7890 5250);
DISPLAY INVISIBLE (-7890 5250);
FORCEPROP 1 LAST CUSTOM_TXT_CDS <NAME_2>
J 0
(-3175 50);
FORCEPROP 1 LAST CUSTOM_TXT_CDS <NAME_1>
J 0
(-3175 175);
FORCEPROP 1 LAST CUSTOM_TXT_CDS <Q_NUMBER>
J 0
(-1403 103);
DISPLAY 1.212766 (-1403 103);
FORCEPROP 1 LAST CUSTOM_TXT_CDS <Q_PROJ>
J 0
(-2382 102);
DISPLAY 1.212766 (-2382 102);
FORCEPROP 1 LAST CUSTOM_TXT_CDS <Q_REV>
J 0
(-184 103);
DISPLAY 1.212766 (-184 103);
FORCEPROP 1 LAST CUSTOM_TXT_CDS <CON_PAGE_NUM> OF <CON_TOTAL_PAGES>
J 0
(-446 18);
DISPLAY 0.978723 (-446 18);
FORCEPROP 1 LAST Q_DEPT BU9
J 1
(-3763 49);
DISPLAY 1.957447 (-3763 49);
PAINT GREEN (-3763 49);
FORCEPROP 1 LAST Q_TITLE CPU0 DDR CHB
J 0
(-9300 50);
DISPLAY 2.446809 (-9300 50);
PAINT GREEN (-9300 50);
FORCEPROP 2 LAST CDS_LIB pure_quanta
J 0
(0 0);
DISPLAY INVISIBLE (0 0);
FORCEPROP 1 LAST CDS_LMAN_SYM_OUTLINE -9475,6775,100,-125
J 0
(0 0);
DISPLAY 0.468085 (0 0);
PAINT GREEN (0 0);
DISPLAY INVISIBLE (0 0);
FORCEPROP 2 LAST PAGE_BORDER TRUE
J 0
(-7890 5250);
DISPLAY 0.638298 (-7890 5250);
PAINT PINK (-7890 5250);
DISPLAY INVISIBLE (-7890 5250);
FORCEPROP 1 LAST COMMENT_BODY TRUE
J 0
(12 -13);
DISPLAY 0.978723 (12 -13);
PAINT GREEN (12 -13);
DISPLAY INVISIBLE (12 -13);
FORCEPROP 2 LAST CDS_XR_PAGE_TITLE CR-11 : @T6G_MB_LIB.T6G(SCH_1):PAGE11
J 0
(-7890 5250);
DISPLAY 0.638298 (-7890 5250);
PAINT PINK (-7890 5250);
DISPLAY INVISIBLE (-7890 5250);
WIRE 17 -1 (-3225 5350)(-3225 5300);
WIRE 17 -1 (-3225 5400)(-3225 5350);
WIRE 17 -1 (-3225 5300)(-3225 5250);
WIRE 17 -1 (-3225 5250)(-3225 5200);
WIRE 17 -1 (-3225 5450)(-3225 5400);
WIRE 17 -1 (-3225 5550)(-3225 5450);
WIRE 17 -1 (-3225 5200)(-3225 5150);
WIRE 17 -1 (-3225 5150)(-3225 5100);
WIRE 17 -1 (-3225 5600)(-3225 5550);
WIRE 17 -1 (-3225 5650)(-3225 5600);
WIRE 17 -1 (-3225 5000)(-3225 5100);
WIRE 17 -1 (-3225 4950)(-3225 5000);
WIRE 17 -1 (-3225 5700)(-3225 5650);
WIRE 17 -1 (-3225 5750)(-3225 5700);
WIRE 17 -1 (-3225 4900)(-3225 4950);
WIRE 17 -1 (-3225 4850)(-3225 4900);
WIRE 17 -1 (-3225 5800)(-3225 5750);
WIRE 17 -1 (-3225 5850)(-3225 5800);
WIRE 17 -1 (-3225 4850)(-3225 4800);
WIRE 17 -1 (-3225 4800)(-3225 4750);
WIRE 17 -1 (-3225 5900)(-3225 5850);
WIRE 17 -1 (-3225 5900)(-2600 5900);
FORCEPROP 2 LAST SIG_NAME M_B_CPU0_SA_DQ<31:0>
J 2
(-2660 5910);
DISPLAY 0.489362 (-2660 5910);
WIRE 17 -1 (-3225 4750)(-3225 4700);
WIRE 17 -1 (-3225 4700)(-3225 4650);
WIRE 17 -1 (-3225 4650)(-3225 4550);
WIRE 17 -1 (-3225 4550)(-3225 4500);
WIRE 17 -1 (-3225 4500)(-3225 4450);
WIRE 17 -1 (-3225 4450)(-3225 4400);
WIRE 17 -1 (-3225 4350)(-3225 4400);
WIRE 17 -1 (-3225 4300)(-3225 4350);
WIRE 17 -1 (-3225 4250)(-3225 4300);
WIRE 17 -1 (-3225 4200)(-3225 4250);
WIRE 17 -1 (-3225 4100)(-3225 4050);
WIRE 17 -1 (-3225 4100)(-2600 4100);
FORCEPROP 2 LAST SIG_NAME M_B_CPU0_SB_DQ<31:0>
J 2
(-2660 4110);
DISPLAY 0.489362 (-2660 4110);
WIRE 17 -1 (-3225 3550)(-3225 3500);
WIRE 17 -1 (-3225 3600)(-3225 3550);
WIRE 17 -1 (-3225 3500)(-3225 3450);
WIRE 17 -1 (-3225 3450)(-3225 3400);
WIRE 17 -1 (-3225 3650)(-3225 3600);
WIRE 17 -1 (-3225 3750)(-3225 3650);
WIRE 17 -1 (-3225 3400)(-3225 3350);
WIRE 17 -1 (-3225 3350)(-3225 3300);
WIRE 17 -1 (-3225 3800)(-3225 3750);
WIRE 17 -1 (-3225 3850)(-3225 3800);
WIRE 17 -1 (-3225 3200)(-3225 3300);
WIRE 17 -1 (-3225 3150)(-3225 3200);
WIRE 17 -1 (-3225 3900)(-3225 3850);
WIRE 17 -1 (-3225 3950)(-3225 3900);
WIRE 17 -1 (-3225 3100)(-3225 3150);
WIRE 17 -1 (-3225 3050)(-3225 3100);
WIRE 17 -1 (-3225 4000)(-3225 3950);
WIRE 17 -1 (-3225 4050)(-3225 4000);
WIRE 17 -1 (-3225 3050)(-3225 3000);
WIRE 17 -1 (-3225 3000)(-3225 2950);
WIRE 17 -1 (-3225 2950)(-3225 2900);
WIRE 17 -1 (-3225 2900)(-3225 2850);
WIRE 17 -1 (-3225 2850)(-3225 2750);
WIRE 17 -1 (-3225 2750)(-3225 2700);
WIRE 17 -1 (-3225 2700)(-3225 2650);
WIRE 17 -1 (-3225 2650)(-3225 2600);
WIRE 17 -1 (-3225 2550)(-3225 2600);
WIRE 17 -1 (-3225 2500)(-3225 2550);
WIRE 17 -1 (-3225 2450)(-3225 2500);
WIRE 17 -1 (-3225 2400)(-3225 2450);
WIRE 17 -1 (-3225 2200)(-3225 2150);
WIRE 17 -1 (-3225 2200)(-3225 2250);
WIRE 17 -1 (-3225 2100)(-3225 2150);
WIRE 17 -1 (-3225 2050)(-3225 2100);
WIRE 17 -1 (-3225 2300)(-3225 2250);
WIRE 17 -1 (-3225 2300)(-3225 2325);
WIRE 17 -1 (-3225 2000)(-3225 2050);
WIRE 17 -1 (-3225 1950)(-3225 2000);
WIRE 17 -1 (-3225 2325)(-2725 2325);
FORCEPROP 2 LAST SIG_NAME M_B_CPU0_SA_CB<7:0>
J 2
(-2725 2335);
DISPLAY 0.489362 (-2725 2335);
WIRE 17 -1 (-3225 1850)(-3225 1875);
WIRE 17 -1 (-3225 1850)(-3225 1800);
WIRE 17 -1 (-3225 1875)(-2725 1875);
FORCEPROP 2 LAST SIG_NAME M_B_CPU0_SB_CB<7:0>
J 2
(-2725 1885);
DISPLAY 0.489362 (-2725 1885);
WIRE 17 -1 (-3225 1750)(-3225 1800);
WIRE 17 -1 (-3225 1750)(-3225 1700);
WIRE 17 -1 (-3225 1650)(-3225 1700);
WIRE 17 -1 (-3225 1600)(-3225 1650);
WIRE 17 -1 (-3225 1550)(-3225 1600);
WIRE 17 -1 (-3225 1500)(-3225 1550);
WIRE 17 -1 (-5950 5850)(-5950 5750);
FORCEPROP 2 LAST SIG_NAME M_B_CPU0_SA_DQS_DN<9:0>
J 2
(-5985 5860);
DISPLAY 0.489362 (-5985 5860);
WIRE 17 -1 (-5950 5650)(-5950 5550);
WIRE 17 -1 (-5950 5750)(-5950 5650);
WIRE 17 -1 (-5950 5550)(-5950 5450);
WIRE 17 -1 (-5950 5350)(-5950 5450);
WIRE 17 -1 (-5950 5250)(-5950 5350);
WIRE 17 -1 (-5950 5150)(-5950 5250);
WIRE 17 -1 (-5950 5150)(-5950 5050);
WIRE 17 -1 (-5750 5900)(-5750 5800);
WIRE 17 -1 (-5750 5900)(-6550 5900);
FORCEPROP 2 LAST SIG_NAME M_B_CPU0_SA_DQS_DP<9:0>
J 2
(-5985 5910);
DISPLAY 0.489362 (-5985 5910);
WIRE 17 -1 (-5950 5050)(-5950 4950);
WIRE 17 -1 (-5750 5800)(-5750 5700);
WIRE 17 -1 (-5750 5700)(-5750 5600);
WIRE 17 -1 (-5750 5600)(-5750 5500);
WIRE 17 -1 (-5750 5400)(-5750 5500);
WIRE 17 -1 (-5750 5300)(-5750 5400);
WIRE 17 -1 (-5750 5200)(-5750 5300);
WIRE 17 -1 (-5750 5200)(-5750 5100);
WIRE 17 -1 (-5750 5100)(-5750 5000);
WIRE 17 -1 (-5750 4350)(-5750 4450);
WIRE 17 -1 (-5750 4250)(-5750 4350);
WIRE 17 -1 (-5750 4550)(-5750 4450);
WIRE 17 -1 (-5750 4650)(-5750 4550);
WIRE 17 -1 (-5750 4150)(-5750 4250);
WIRE 17 -1 (-5750 4150)(-5750 4050);
WIRE 17 -1 (-5750 4750)(-5750 4650);
WIRE 17 -1 (-5750 4850)(-5750 4750);
WIRE 17 -1 (-5750 4050)(-5750 3950);
WIRE 17 -1 (-5750 4850)(-6550 4850);
FORCEPROP 2 LAST SIG_NAME M_B_CPU0_SB_DQS_DP<9:0>
J 2
(-5985 4860);
DISPLAY 0.489362 (-5985 4860);
WIRE 17 -1 (-5950 4800)(-5950 4700);
FORCEPROP 2 LAST SIG_NAME M_B_CPU0_SB_DQS_DN<9:0>
J 2
(-5985 4810);
DISPLAY 0.489362 (-5985 4810);
WIRE 17 -1 (-5950 4600)(-5950 4500);
WIRE 17 -1 (-5950 4700)(-5950 4600);
WIRE 17 -1 (-5950 4500)(-5950 4400);
WIRE 17 -1 (-5950 4300)(-5950 4400);
WIRE 17 -1 (-5950 4200)(-5950 4300);
WIRE 17 -1 (-5950 4100)(-5950 4200);
WIRE 17 -1 (-5950 4100)(-5950 4000);
WIRE 17 -1 (-5950 4000)(-5950 3900);
WIRE 17 -1 (-5950 3700)(-5950 3750);
WIRE 17 -1 (-5950 3650)(-5950 3700);
WIRE 17 -1 (-5950 3750)(-6450 3750);
FORCEPROP 2 LAST SIG_NAME M_B_CPU0_SA_CA<6:0>
J 0
(-6450 3760);
DISPLAY 0.489362 (-6450 3760);
WIRE 17 -1 (-5950 3300)(-5950 3350);
WIRE 17 -1 (-5950 3250)(-5950 3300);
WIRE 17 -1 (-5950 3350)(-6450 3350);
FORCEPROP 2 LAST SIG_NAME M_B_CPU0_SB_CA<6:0>
J 0
(-6450 3360);
DISPLAY 0.489362 (-6450 3360);
WIRE 17 -1 (-5950 3600)(-5950 3650);
WIRE 17 -1 (-5950 3200)(-5950 3250);
WIRE 17 -1 (-5950 3550)(-5950 3600);
WIRE 17 -1 (-5950 3500)(-5950 3550);
WIRE 17 -1 (-5950 3450)(-5950 3500);
WIRE 17 -1 (-5950 3150)(-5950 3200);
WIRE 17 -1 (-5950 3100)(-5950 3150);
WIRE 17 -1 (-5950 3050)(-5950 3100);
WIRE 17 -1 (-5950 5850)(-6550 5850);
WIRE 17 -1 (-5950 4800)(-6550 4800);
WIRE 16 -1 (-7650 2025)(-6925 2025);
FORCEPROP 2 LAST SIG_NAME M_B_CPU0_ALERT_N
J 0
(-7610 2035);
DISPLAY 0.489362 (-7610 2035);
WIRE 16 -1 (-6450 1075)(-5350 1075);
FORCEPROP 2 LAST SIG_NAME TP_M_B_CPU0_SA_TEST39B
J 0
(-6435 1085);
DISPLAY 0.489362 (-6435 1085);
FORCEPROP 2 LASTPROP $XRERR UNIQUE?
J 0
(-6690 1075);
DISPLAY 0.638298 (-6690 1075);
PAINT MONO (-6690 1075);
DISPLAY INVISIBLE (-6690 1075);
WIRE 16 -1 (-6725 2025)(-5350 2025);
FORCEPROP 2 LAST SIG_NAME M_B_CPU0_ALERT_R_N
J 0
(-6435 2035);
DISPLAY 0.489362 (-6435 2035);
FORCEPROP 2 LASTPROP $XRERR UNIQUE?
J 0
(-6675 2035);
DISPLAY 0.638298 (-6675 2035);
PAINT MONO (-6675 2035);
DISPLAY INVISIBLE (-6675 2035);
WIRE 16 -1 (-6450 2875)(-5350 2875);
FORCEPROP 2 LAST SIG_NAME M_B_CPU0_CLK_DP<0>
J 0
(-6450 2885);
DISPLAY 0.489362 (-6450 2885);
WIRE 16 -1 (-6450 2825)(-5350 2825);
FORCEPROP 2 LAST SIG_NAME M_B_CPU0_CLK_DN<0>
J 0
(-6450 2835);
DISPLAY 0.489362 (-6450 2835);
WIRE 16 -1 (-6450 2725)(-5350 2725);
FORCEPROP 2 LAST SIG_NAME M_B_CPU0_SA_CS_N<0>
J 0
(-6450 2735);
DISPLAY 0.489362 (-6450 2735);
WIRE 16 -1 (-6450 2675)(-5350 2675);
FORCEPROP 2 LAST SIG_NAME M_B_CPU0_SA_CS_N<1>
J 0
(-6450 2685);
DISPLAY 0.489362 (-6450 2685);
WIRE 16 -1 (-6450 2475)(-5350 2475);
FORCEPROP 2 LAST SIG_NAME M_B_CPU0_SA_PAR
J 0
(-6450 2485);
DISPLAY 0.489362 (-6450 2485);
WIRE 16 -1 (-6450 2375)(-5350 2375);
FORCEPROP 2 LAST SIG_NAME M_B_CPU0_SB_CS_N<0>
J 0
(-6450 2385);
DISPLAY 0.489362 (-6450 2385);
WIRE 16 -1 (-6450 2575)(-5350 2575);
FORCEPROP 2 LAST SIG_NAME M_B_CPU0_SA_RSP<0>
J 0
(-6450 2585);
DISPLAY 0.489362 (-6450 2585);
WIRE 16 -1 (-6450 2325)(-5350 2325);
FORCEPROP 2 LAST SIG_NAME M_B_CPU0_SB_CS_N<1>
J 0
(-6450 2335);
DISPLAY 0.489362 (-6450 2335);
WIRE 16 -1 (-6450 2125)(-5350 2125);
FORCEPROP 2 LAST SIG_NAME M_B_CPU0_SB_PAR
J 0
(-6450 2135);
DISPLAY 0.489362 (-6450 2135);
WIRE 16 -1 (-6450 2225)(-5350 2225);
FORCEPROP 2 LAST SIG_NAME M_B_CPU0_SB_RSP<0>
J 0
(-6450 2235);
DISPLAY 0.489362 (-6450 2235);
WIRE 16 -1 (-6450 1925)(-5350 1925);
FORCEPROP 2 LAST SIG_NAME M_B_CPU0_RESET_N
J 0
(-6450 1935);
DISPLAY 0.489362 (-6450 1935);
WIRE 16 -1 (-5850 3025)(-5350 3025);
WIRE 16 -1 (-5650 3925)(-5350 3925);
WIRE 16 -1 (-5850 3975)(-5350 3975);
WIRE 16 -1 (-5850 4075)(-5350 4075);
WIRE 16 -1 (-5850 3425)(-5350 3425);
WIRE 16 -1 (-5850 3075)(-5350 3075);
WIRE 16 -1 (-5850 3475)(-5350 3475);
WIRE 16 -1 (-5850 3125)(-5350 3125);
WIRE 16 -1 (-5850 3525)(-5350 3525);
WIRE 16 -1 (-5850 3175)(-5350 3175);
WIRE 16 -1 (-5850 3575)(-5350 3575);
WIRE 16 -1 (-5850 3225)(-5350 3225);
WIRE 16 -1 (-5850 3625)(-5350 3625);
WIRE 16 -1 (-5850 3275)(-5350 3275);
WIRE 16 -1 (-5850 3675)(-5350 3675);
WIRE 16 -1 (-5850 3325)(-5350 3325);
WIRE 16 -1 (-5850 3725)(-5350 3725);
WIRE 16 -1 (-5650 4025)(-5350 4025);
WIRE 16 -1 (-5850 3875)(-5350 3875);
WIRE 16 -1 (-5650 4425)(-5350 4425);
WIRE 16 -1 (-5650 4975)(-5350 4975);
WIRE 16 -1 (-5650 4525)(-5350 4525);
WIRE 16 -1 (-5650 5075)(-5350 5075);
WIRE 16 -1 (-5650 4625)(-5350 4625);
WIRE 16 -1 (-5850 4175)(-5350 4175);
WIRE 16 -1 (-5650 4725)(-5350 4725);
WIRE 16 -1 (-5850 4275)(-5350 4275);
WIRE 16 -1 (-5650 4825)(-5350 4825);
WIRE 16 -1 (-5850 4375)(-5350 4375);
WIRE 16 -1 (-5850 4925)(-5350 4925);
WIRE 16 -1 (-5850 4475)(-5350 4475);
WIRE 16 -1 (-5850 5025)(-5350 5025);
WIRE 16 -1 (-5850 4575)(-5350 4575);
WIRE 16 -1 (-5850 4675)(-5350 4675);
WIRE 16 -1 (-5850 4775)(-5350 4775);
WIRE 16 -1 (-5650 4125)(-5350 4125);
WIRE 16 -1 (-5650 4225)(-5350 4225);
WIRE 16 -1 (-5650 4325)(-5350 4325);
WIRE 16 -1 (-5650 5175)(-5350 5175);
WIRE 16 -1 (-5650 5275)(-5350 5275);
WIRE 16 -1 (-5650 5375)(-5350 5375);
WIRE 16 -1 (-5650 5475)(-5350 5475);
WIRE 16 -1 (-5650 5575)(-5350 5575);
WIRE 16 -1 (-5850 5125)(-5350 5125);
WIRE 16 -1 (-5650 5675)(-5350 5675);
WIRE 16 -1 (-5850 5225)(-5350 5225);
WIRE 16 -1 (-5650 5775)(-5350 5775);
WIRE 16 -1 (-5850 5325)(-5350 5325);
WIRE 16 -1 (-5650 5875)(-5350 5875);
WIRE 16 -1 (-5850 5425)(-5350 5425);
WIRE 16 -1 (-5850 5525)(-5350 5525);
WIRE 16 -1 (-5850 5625)(-5350 5625);
WIRE 16 -1 (-5850 5725)(-5350 5725);
WIRE 16 -1 (-5850 5825)(-5350 5825);
WIRE 16 -1 (-3750 1475)(-3325 1475);
WIRE 16 -1 (-3750 1525)(-3325 1525);
WIRE 16 -1 (-3750 1575)(-3325 1575);
WIRE 16 -1 (-3750 1625)(-3325 1625);
WIRE 16 -1 (-3750 1675)(-3325 1675);
WIRE 16 -1 (-3750 1725)(-3325 1725);
WIRE 16 -1 (-3750 1925)(-3325 1925);
WIRE 16 -1 (-3750 1775)(-3325 1775);
WIRE 16 -1 (-3750 1975)(-3325 1975);
WIRE 16 -1 (-3750 1825)(-3325 1825);
WIRE 16 -1 (-3750 2025)(-3325 2025);
WIRE 16 -1 (-3750 2975)(-3325 2975);
WIRE 16 -1 (-3750 3025)(-3325 3025);
WIRE 16 -1 (-3750 2225)(-3325 2225);
WIRE 16 -1 (-3750 2275)(-3325 2275);
WIRE 16 -1 (-3750 2475)(-3325 2475);
WIRE 16 -1 (-3750 2525)(-3325 2525);
WIRE 16 -1 (-3750 2575)(-3325 2575);
WIRE 16 -1 (-3750 2625)(-3325 2625);
WIRE 16 -1 (-3750 2675)(-3325 2675);
WIRE 16 -1 (-3750 2725)(-3325 2725);
WIRE 16 -1 (-3750 2825)(-3325 2825);
WIRE 16 -1 (-3750 2875)(-3325 2875);
WIRE 16 -1 (-3750 2925)(-3325 2925);
WIRE 16 -1 (-3750 2375)(-3325 2375);
WIRE 16 -1 (-3750 2425)(-3325 2425);
WIRE 16 -1 (-3750 2075)(-3325 2075);
WIRE 16 -1 (-3750 2125)(-3325 2125);
WIRE 16 -1 (-3750 2175)(-3325 2175);
WIRE 16 -1 (-3750 3075)(-3325 3075);
WIRE 16 -1 (-3750 3575)(-3325 3575);
WIRE 16 -1 (-3750 3125)(-3325 3125);
WIRE 16 -1 (-3750 3625)(-3325 3625);
WIRE 16 -1 (-3750 3175)(-3325 3175);
WIRE 16 -1 (-3750 3725)(-3325 3725);
WIRE 16 -1 (-3750 3275)(-3325 3275);
WIRE 16 -1 (-3750 3775)(-3325 3775);
WIRE 16 -1 (-3750 3325)(-3325 3325);
WIRE 16 -1 (-3750 3825)(-3325 3825);
WIRE 16 -1 (-3750 3375)(-3325 3375);
WIRE 16 -1 (-3750 3875)(-3325 3875);
WIRE 16 -1 (-3750 3425)(-3325 3425);
WIRE 16 -1 (-3750 3925)(-3325 3925);
WIRE 16 -1 (-3750 3475)(-3325 3475);
WIRE 16 -1 (-3750 3975)(-3325 3975);
WIRE 16 -1 (-3750 3525)(-3325 3525);
WIRE 16 -1 (-3750 4025)(-3325 4025);
WIRE 16 -1 (-3750 4075)(-3325 4075);
WIRE 16 -1 (-3750 4525)(-3325 4525);
WIRE 16 -1 (-3750 4725)(-3325 4725);
WIRE 16 -1 (-3750 4775)(-3325 4775);
WIRE 16 -1 (-3750 4175)(-3325 4175);
WIRE 16 -1 (-3750 4225)(-3325 4225);
WIRE 16 -1 (-3750 4825)(-3325 4825);
WIRE 16 -1 (-3750 4875)(-3325 4875);
WIRE 16 -1 (-3750 4275)(-3325 4275);
WIRE 16 -1 (-3750 4925)(-3325 4925);
WIRE 16 -1 (-3750 4325)(-3325 4325);
WIRE 16 -1 (-3750 4975)(-3325 4975);
WIRE 16 -1 (-3750 4375)(-3325 4375);
WIRE 16 -1 (-3750 5075)(-3325 5075);
WIRE 16 -1 (-3750 4425)(-3325 4425);
WIRE 16 -1 (-3750 4475)(-3325 4475);
WIRE 16 -1 (-3750 4625)(-3325 4625);
WIRE 16 -1 (-3750 4675)(-3325 4675);
WIRE 16 -1 (-3750 5325)(-3325 5325);
WIRE 16 -1 (-3750 5375)(-3325 5375);
WIRE 16 -1 (-3750 5425)(-3325 5425);
WIRE 16 -1 (-3750 5525)(-3325 5525);
WIRE 16 -1 (-3750 5575)(-3325 5575);
WIRE 16 -1 (-3750 5625)(-3325 5625);
WIRE 16 -1 (-3750 5675)(-3325 5675);
WIRE 16 -1 (-3750 5725)(-3325 5725);
WIRE 16 -1 (-3750 5775)(-3325 5775);
WIRE 16 -1 (-3750 5825)(-3325 5825);
WIRE 16 -1 (-3750 5125)(-3325 5125);
WIRE 16 -1 (-3750 5875)(-3325 5875);
WIRE 16 -1 (-3750 5175)(-3325 5175);
WIRE 16 -1 (-3750 5225)(-3325 5225);
WIRE 16 -1 (-3750 5275)(-3325 5275);
QUIT
